FILE_TYPE = MACRO_DRAWING;
SET COLOR_WIRE YELLOW;
SET COLOR_PROP MONO;
SET COLOR_DOT WHITE;
SET COLOR_ARC YELLOW;
SET COLOR_BODY GREEN;
SET COLOR_NOTE MONO;
SET PROP_DISPLAY VALUE;
SET PAGE_NUMBER P57;
FORCEADD OFFPAGE..5
(-6425 525);
FORCEPROP 2 LAST $XR0 77 
J 0
(-6679 525);
DISPLAY 0.638298 (-6679 525);
PAINT MONO (-6679 525);
FORCEPROP 2 LAST $XR1 78 
J 0
(-6769 525);
DISPLAY 0.638298 (-6769 525);
PAINT MONO (-6769 525);
FORCEPROP 2 LAST CDS_LIB mstr_standard
J 0
(-6425 525);
PAINT MONO (-6425 525);
DISPLAY INVISIBLE (-6425 525);
FORCEPROP 1 LAST OFFPAGE TRUE
J 0
(-6100 400);
DISPLAY 1.170213 (-6100 400);
PAINT GREEN (-6100 400);
DISPLAY INVISIBLE (-6100 400);
FORCEPROP 1 LAST COMMENT_BODY TRUE
J 0
(-6325 450);
DISPLAY 1.170213 (-6325 450);
PAINT GREEN (-6325 450);
DISPLAY INVISIBLE (-6325 450);
FORCEPROP 2 LAST PATH I1
J 0
(-6375 600);
DISPLAY 1.021277 (-6375 600);
PAINT ORANGE (-6375 600);
DISPLAY INVISIBLE (-6375 600);
FORCEADD TAP..6
(-5575 825);
FORCEPROP 3 LASTPIN (-5525 825) SIG_NAME M_G_CLK_DP<0>
J 0
(-5515 835);
DISPLAY 0.659574 (-5515 835);
PAINT MONO (-5515 835);
DISPLAY INVISIBLE (-5515 835);
FORCEPROP 1 LASTPIN (-5525 825) BN 0
J 0
(-5577 833);
DISPLAY 0.617021 (-5577 833);
PAINT GREEN (-5577 833);
FORCEPROP 2 LAST CDS_LIB mstr_standard
J 0
(-5575 825);
PAINT MONO (-5575 825);
DISPLAY INVISIBLE (-5575 825);
FORCEPROP 1 LAST BODY_TYPE PLUMBING
J 0
(-5575 775);
DISPLAY 1.595745 (-5575 775);
PAINT GREEN (-5575 775);
DISPLAY INVISIBLE (-5575 775);
FORCEPROP 1 LAST HDL_TAP TRUE
J 0
(-5250 700);
DISPLAY 1.595745 (-5250 700);
PAINT GREEN (-5250 700);
DISPLAY INVISIBLE (-5250 700);
FORCEPROP 1 LAST PATH I10
J 0
(-5577 825);
DISPLAY 0.872340 (-5577 825);
PAINT GREEN (-5577 825);
DISPLAY INVISIBLE (-5577 825);
FORCEADD TAP..6
R 2
(-2850 1575);
FORCEPROP 3 LASTPIN (-2900 1575) SIG_NAME M_G_ODT<3>
J 0
(-2890 1585);
DISPLAY 0.659574 (-2890 1585);
PAINT MONO (-2890 1585);
DISPLAY INVISIBLE (-2890 1585);
FORCEPROP 1 LASTPIN (-2900 1575) BN 3
J 2
(-2848 1583);
DISPLAY 0.617021 (-2848 1583);
PAINT GREEN (-2848 1583);
FORCEPROP 2 LAST CDS_LIB mstr_standard
J 0
(-2850 1575);
PAINT MONO (-2850 1575);
DISPLAY INVISIBLE (-2850 1575);
FORCEPROP 1 LAST BODY_TYPE PLUMBING
J 2
(-2850 1525);
DISPLAY 1.595745 (-2850 1525);
PAINT GREEN (-2850 1525);
DISPLAY INVISIBLE (-2850 1525);
FORCEPROP 1 LAST HDL_TAP TRUE
J 2
(-3175 1450);
DISPLAY 1.595745 (-3175 1450);
PAINT GREEN (-3175 1450);
DISPLAY INVISIBLE (-3175 1450);
FORCEPROP 1 LAST PATH I100
J 2
(-2848 1575);
DISPLAY 0.872340 (-2848 1575);
PAINT GREEN (-2848 1575);
DISPLAY INVISIBLE (-2848 1575);
FORCEADD TAP..6
R 2
(-2850 1525);
FORCEPROP 3 LASTPIN (-2900 1525) SIG_NAME M_G_ODT<2>
J 0
(-2890 1535);
DISPLAY 0.659574 (-2890 1535);
PAINT MONO (-2890 1535);
DISPLAY INVISIBLE (-2890 1535);
FORCEPROP 1 LASTPIN (-2900 1525) BN 2
J 2
(-2848 1533);
DISPLAY 0.617021 (-2848 1533);
PAINT GREEN (-2848 1533);
FORCEPROP 2 LAST CDS_LIB mstr_standard
J 0
(-2850 1525);
PAINT MONO (-2850 1525);
DISPLAY INVISIBLE (-2850 1525);
FORCEPROP 1 LAST BODY_TYPE PLUMBING
J 2
(-2850 1475);
DISPLAY 1.595745 (-2850 1475);
PAINT GREEN (-2850 1475);
DISPLAY INVISIBLE (-2850 1475);
FORCEPROP 1 LAST HDL_TAP TRUE
J 2
(-3175 1400);
DISPLAY 1.595745 (-3175 1400);
PAINT GREEN (-3175 1400);
DISPLAY INVISIBLE (-3175 1400);
FORCEPROP 1 LAST PATH I101
J 2
(-2848 1525);
DISPLAY 0.872340 (-2848 1525);
PAINT GREEN (-2848 1525);
DISPLAY INVISIBLE (-2848 1525);
FORCEADD TAP..6
R 2
(-2850 1475);
FORCEPROP 3 LASTPIN (-2900 1475) SIG_NAME M_G_ODT<1>
J 0
(-2890 1485);
DISPLAY 0.659574 (-2890 1485);
PAINT MONO (-2890 1485);
DISPLAY INVISIBLE (-2890 1485);
FORCEPROP 1 LASTPIN (-2900 1475) BN 1
J 2
(-2848 1483);
DISPLAY 0.617021 (-2848 1483);
PAINT GREEN (-2848 1483);
FORCEPROP 2 LAST CDS_LIB mstr_standard
J 0
(-2850 1475);
PAINT MONO (-2850 1475);
DISPLAY INVISIBLE (-2850 1475);
FORCEPROP 1 LAST BODY_TYPE PLUMBING
J 2
(-2850 1425);
DISPLAY 1.595745 (-2850 1425);
PAINT GREEN (-2850 1425);
DISPLAY INVISIBLE (-2850 1425);
FORCEPROP 1 LAST HDL_TAP TRUE
J 2
(-3175 1350);
DISPLAY 1.595745 (-3175 1350);
PAINT GREEN (-3175 1350);
DISPLAY INVISIBLE (-3175 1350);
FORCEPROP 1 LAST PATH I102
J 2
(-2848 1475);
DISPLAY 0.872340 (-2848 1475);
PAINT GREEN (-2848 1475);
DISPLAY INVISIBLE (-2848 1475);
FORCEADD TAP..6
R 2
(-2850 1675);
FORCEPROP 3 LASTPIN (-2900 1675) SIG_NAME M_G_CKE<0>
J 0
(-2890 1685);
DISPLAY 0.659574 (-2890 1685);
PAINT MONO (-2890 1685);
DISPLAY INVISIBLE (-2890 1685);
FORCEPROP 1 LASTPIN (-2900 1675) BN 0
J 2
(-2848 1683);
DISPLAY 0.617021 (-2848 1683);
PAINT GREEN (-2848 1683);
FORCEPROP 2 LAST CDS_LIB mstr_standard
J 0
(-2850 1675);
PAINT MONO (-2850 1675);
DISPLAY INVISIBLE (-2850 1675);
FORCEPROP 1 LAST BODY_TYPE PLUMBING
J 2
(-2850 1625);
DISPLAY 1.595745 (-2850 1625);
PAINT GREEN (-2850 1625);
DISPLAY INVISIBLE (-2850 1625);
FORCEPROP 1 LAST HDL_TAP TRUE
J 2
(-3175 1550);
DISPLAY 1.595745 (-3175 1550);
PAINT GREEN (-3175 1550);
DISPLAY INVISIBLE (-3175 1550);
FORCEPROP 1 LAST PATH I103
J 2
(-2848 1675);
DISPLAY 0.872340 (-2848 1675);
PAINT GREEN (-2848 1675);
DISPLAY INVISIBLE (-2848 1675);
FORCEADD TAP..6
R 2
(-2850 1725);
FORCEPROP 3 LASTPIN (-2900 1725) SIG_NAME M_G_CKE<1>
J 0
(-2890 1735);
DISPLAY 0.659574 (-2890 1735);
PAINT MONO (-2890 1735);
DISPLAY INVISIBLE (-2890 1735);
FORCEPROP 1 LASTPIN (-2900 1725) BN 1
J 2
(-2848 1733);
DISPLAY 0.617021 (-2848 1733);
PAINT GREEN (-2848 1733);
FORCEPROP 2 LAST CDS_LIB mstr_standard
J 0
(-2850 1725);
PAINT MONO (-2850 1725);
DISPLAY INVISIBLE (-2850 1725);
FORCEPROP 1 LAST BODY_TYPE PLUMBING
J 2
(-2850 1675);
DISPLAY 1.595745 (-2850 1675);
PAINT GREEN (-2850 1675);
DISPLAY INVISIBLE (-2850 1675);
FORCEPROP 1 LAST HDL_TAP TRUE
J 2
(-3175 1600);
DISPLAY 1.595745 (-3175 1600);
PAINT GREEN (-3175 1600);
DISPLAY INVISIBLE (-3175 1600);
FORCEPROP 1 LAST PATH I104
J 2
(-2848 1725);
DISPLAY 0.872340 (-2848 1725);
PAINT GREEN (-2848 1725);
DISPLAY INVISIBLE (-2848 1725);
FORCEADD TAP..6
R 2
(-2850 1775);
FORCEPROP 3 LASTPIN (-2900 1775) SIG_NAME M_G_CKE<2>
J 0
(-2890 1785);
DISPLAY 0.659574 (-2890 1785);
PAINT MONO (-2890 1785);
DISPLAY INVISIBLE (-2890 1785);
FORCEPROP 1 LASTPIN (-2900 1775) BN 2
J 2
(-2848 1783);
DISPLAY 0.617021 (-2848 1783);
PAINT GREEN (-2848 1783);
FORCEPROP 2 LAST CDS_LIB mstr_standard
J 0
(-2850 1775);
PAINT MONO (-2850 1775);
DISPLAY INVISIBLE (-2850 1775);
FORCEPROP 1 LAST BODY_TYPE PLUMBING
J 2
(-2850 1725);
DISPLAY 1.595745 (-2850 1725);
PAINT GREEN (-2850 1725);
DISPLAY INVISIBLE (-2850 1725);
FORCEPROP 1 LAST HDL_TAP TRUE
J 2
(-3175 1650);
DISPLAY 1.595745 (-3175 1650);
PAINT GREEN (-3175 1650);
DISPLAY INVISIBLE (-3175 1650);
FORCEPROP 1 LAST PATH I105
J 2
(-2848 1775);
DISPLAY 0.872340 (-2848 1775);
PAINT GREEN (-2848 1775);
DISPLAY INVISIBLE (-2848 1775);
FORCEADD TAP..6
R 2
(-2850 1825);
FORCEPROP 3 LASTPIN (-2900 1825) SIG_NAME M_G_CKE<3>
J 0
(-2890 1835);
DISPLAY 0.659574 (-2890 1835);
PAINT MONO (-2890 1835);
DISPLAY INVISIBLE (-2890 1835);
FORCEPROP 1 LASTPIN (-2900 1825) BN 3
J 2
(-2848 1833);
DISPLAY 0.617021 (-2848 1833);
PAINT GREEN (-2848 1833);
FORCEPROP 2 LAST CDS_LIB mstr_standard
J 0
(-2850 1825);
PAINT MONO (-2850 1825);
DISPLAY INVISIBLE (-2850 1825);
FORCEPROP 1 LAST BODY_TYPE PLUMBING
J 2
(-2850 1775);
DISPLAY 1.595745 (-2850 1775);
PAINT GREEN (-2850 1775);
DISPLAY INVISIBLE (-2850 1775);
FORCEPROP 1 LAST HDL_TAP TRUE
J 2
(-3175 1700);
DISPLAY 1.595745 (-3175 1700);
PAINT GREEN (-3175 1700);
DISPLAY INVISIBLE (-3175 1700);
FORCEPROP 1 LAST PATH I106
J 2
(-2848 1825);
DISPLAY 0.872340 (-2848 1825);
PAINT GREEN (-2848 1825);
DISPLAY INVISIBLE (-2848 1825);
FORCEADD TAP..6
R 2
(-2850 1925);
FORCEPROP 3 LASTPIN (-2900 1925) SIG_NAME M_G_MA<0>
J 0
(-2890 1935);
DISPLAY 0.659574 (-2890 1935);
PAINT MONO (-2890 1935);
DISPLAY INVISIBLE (-2890 1935);
FORCEPROP 1 LASTPIN (-2900 1925) BN 0
J 2
(-2848 1933);
DISPLAY 0.617021 (-2848 1933);
PAINT GREEN (-2848 1933);
FORCEPROP 2 LAST CDS_LIB mstr_standard
J 0
(-2850 1925);
PAINT MONO (-2850 1925);
DISPLAY INVISIBLE (-2850 1925);
FORCEPROP 1 LAST BODY_TYPE PLUMBING
J 2
(-2850 1875);
DISPLAY 1.595745 (-2850 1875);
PAINT GREEN (-2850 1875);
DISPLAY INVISIBLE (-2850 1875);
FORCEPROP 1 LAST HDL_TAP TRUE
J 2
(-3175 1800);
DISPLAY 1.595745 (-3175 1800);
PAINT GREEN (-3175 1800);
DISPLAY INVISIBLE (-3175 1800);
FORCEPROP 1 LAST PATH I107
J 2
(-2848 1925);
DISPLAY 0.872340 (-2848 1925);
PAINT GREEN (-2848 1925);
DISPLAY INVISIBLE (-2848 1925);
FORCEADD TAP..6
R 2
(-2850 1975);
FORCEPROP 3 LASTPIN (-2900 1975) SIG_NAME M_G_MA<1>
J 0
(-2890 1985);
DISPLAY 0.659574 (-2890 1985);
PAINT MONO (-2890 1985);
DISPLAY INVISIBLE (-2890 1985);
FORCEPROP 1 LASTPIN (-2900 1975) BN 1
J 2
(-2848 1983);
DISPLAY 0.617021 (-2848 1983);
PAINT GREEN (-2848 1983);
FORCEPROP 2 LAST CDS_LIB mstr_standard
J 0
(-2850 1975);
PAINT MONO (-2850 1975);
DISPLAY INVISIBLE (-2850 1975);
FORCEPROP 1 LAST BODY_TYPE PLUMBING
J 2
(-2850 1925);
DISPLAY 1.595745 (-2850 1925);
PAINT GREEN (-2850 1925);
DISPLAY INVISIBLE (-2850 1925);
FORCEPROP 1 LAST HDL_TAP TRUE
J 2
(-3175 1850);
DISPLAY 1.595745 (-3175 1850);
PAINT GREEN (-3175 1850);
DISPLAY INVISIBLE (-3175 1850);
FORCEPROP 1 LAST PATH I108
J 2
(-2848 1975);
DISPLAY 0.872340 (-2848 1975);
PAINT GREEN (-2848 1975);
DISPLAY INVISIBLE (-2848 1975);
FORCEADD TAP..6
R 2
(-2850 2075);
FORCEPROP 3 LASTPIN (-2900 2075) SIG_NAME M_G_MA<3>
J 0
(-2890 2085);
DISPLAY 0.659574 (-2890 2085);
PAINT MONO (-2890 2085);
DISPLAY INVISIBLE (-2890 2085);
FORCEPROP 1 LASTPIN (-2900 2075) BN 3
J 2
(-2848 2083);
DISPLAY 0.617021 (-2848 2083);
PAINT GREEN (-2848 2083);
FORCEPROP 2 LAST CDS_LIB mstr_standard
J 0
(-2850 2075);
PAINT MONO (-2850 2075);
DISPLAY INVISIBLE (-2850 2075);
FORCEPROP 1 LAST BODY_TYPE PLUMBING
J 2
(-2850 2025);
DISPLAY 1.595745 (-2850 2025);
PAINT GREEN (-2850 2025);
DISPLAY INVISIBLE (-2850 2025);
FORCEPROP 1 LAST HDL_TAP TRUE
J 2
(-3175 1950);
DISPLAY 1.595745 (-3175 1950);
PAINT GREEN (-3175 1950);
DISPLAY INVISIBLE (-3175 1950);
FORCEPROP 1 LAST PATH I109
J 2
(-2848 2075);
DISPLAY 0.872340 (-2848 2075);
PAINT GREEN (-2848 2075);
DISPLAY INVISIBLE (-2848 2075);
FORCEADD TAP..6
(-5575 925);
FORCEPROP 3 LASTPIN (-5525 925) SIG_NAME M_G_CLK_DP<2>
J 0
(-5515 935);
DISPLAY 0.659574 (-5515 935);
PAINT MONO (-5515 935);
DISPLAY INVISIBLE (-5515 935);
FORCEPROP 1 LASTPIN (-5525 925) BN 2
J 0
(-5577 933);
DISPLAY 0.617021 (-5577 933);
PAINT GREEN (-5577 933);
FORCEPROP 2 LAST CDS_LIB mstr_standard
J 0
(-5575 925);
PAINT MONO (-5575 925);
DISPLAY INVISIBLE (-5575 925);
FORCEPROP 1 LAST BODY_TYPE PLUMBING
J 0
(-5575 875);
DISPLAY 1.595745 (-5575 875);
PAINT GREEN (-5575 875);
DISPLAY INVISIBLE (-5575 875);
FORCEPROP 1 LAST HDL_TAP TRUE
J 0
(-5250 800);
DISPLAY 1.595745 (-5250 800);
PAINT GREEN (-5250 800);
DISPLAY INVISIBLE (-5250 800);
FORCEPROP 1 LAST PATH I11
J 0
(-5577 925);
DISPLAY 0.872340 (-5577 925);
PAINT GREEN (-5577 925);
DISPLAY INVISIBLE (-5577 925);
FORCEADD TAP..6
R 2
(-2850 2025);
FORCEPROP 3 LASTPIN (-2900 2025) SIG_NAME M_G_MA<2>
J 0
(-2890 2035);
DISPLAY 0.659574 (-2890 2035);
PAINT MONO (-2890 2035);
DISPLAY INVISIBLE (-2890 2035);
FORCEPROP 1 LASTPIN (-2900 2025) BN 2
J 2
(-2848 2033);
DISPLAY 0.617021 (-2848 2033);
PAINT GREEN (-2848 2033);
FORCEPROP 2 LAST CDS_LIB mstr_standard
J 0
(-2850 2025);
PAINT MONO (-2850 2025);
DISPLAY INVISIBLE (-2850 2025);
FORCEPROP 1 LAST BODY_TYPE PLUMBING
J 2
(-2850 1975);
DISPLAY 1.595745 (-2850 1975);
PAINT GREEN (-2850 1975);
DISPLAY INVISIBLE (-2850 1975);
FORCEPROP 1 LAST HDL_TAP TRUE
J 2
(-3175 1900);
DISPLAY 1.595745 (-3175 1900);
PAINT GREEN (-3175 1900);
DISPLAY INVISIBLE (-3175 1900);
FORCEPROP 1 LAST PATH I110
J 2
(-2848 2025);
DISPLAY 0.872340 (-2848 2025);
PAINT GREEN (-2848 2025);
DISPLAY INVISIBLE (-2848 2025);
FORCEADD TAP..6
R 2
(-2850 2125);
FORCEPROP 3 LASTPIN (-2900 2125) SIG_NAME M_G_MA<4>
J 0
(-2890 2135);
DISPLAY 0.659574 (-2890 2135);
PAINT MONO (-2890 2135);
DISPLAY INVISIBLE (-2890 2135);
FORCEPROP 1 LASTPIN (-2900 2125) BN 4
J 2
(-2848 2133);
DISPLAY 0.617021 (-2848 2133);
PAINT GREEN (-2848 2133);
FORCEPROP 2 LAST CDS_LIB mstr_standard
J 0
(-2850 2125);
PAINT MONO (-2850 2125);
DISPLAY INVISIBLE (-2850 2125);
FORCEPROP 1 LAST BODY_TYPE PLUMBING
J 2
(-2850 2075);
DISPLAY 1.595745 (-2850 2075);
PAINT GREEN (-2850 2075);
DISPLAY INVISIBLE (-2850 2075);
FORCEPROP 1 LAST HDL_TAP TRUE
J 2
(-3175 2000);
DISPLAY 1.595745 (-3175 2000);
PAINT GREEN (-3175 2000);
DISPLAY INVISIBLE (-3175 2000);
FORCEPROP 1 LAST PATH I111
J 2
(-2848 2125);
DISPLAY 0.872340 (-2848 2125);
PAINT GREEN (-2848 2125);
DISPLAY INVISIBLE (-2848 2125);
FORCEADD TAP..6
R 2
(-2850 2175);
FORCEPROP 3 LASTPIN (-2900 2175) SIG_NAME M_G_MA<5>
J 0
(-2890 2185);
DISPLAY 0.659574 (-2890 2185);
PAINT MONO (-2890 2185);
DISPLAY INVISIBLE (-2890 2185);
FORCEPROP 1 LASTPIN (-2900 2175) BN 5
J 2
(-2848 2183);
DISPLAY 0.617021 (-2848 2183);
PAINT GREEN (-2848 2183);
FORCEPROP 2 LAST CDS_LIB mstr_standard
J 0
(-2850 2175);
PAINT MONO (-2850 2175);
DISPLAY INVISIBLE (-2850 2175);
FORCEPROP 1 LAST BODY_TYPE PLUMBING
J 2
(-2850 2125);
DISPLAY 1.595745 (-2850 2125);
PAINT GREEN (-2850 2125);
DISPLAY INVISIBLE (-2850 2125);
FORCEPROP 1 LAST HDL_TAP TRUE
J 2
(-3175 2050);
DISPLAY 1.595745 (-3175 2050);
PAINT GREEN (-3175 2050);
DISPLAY INVISIBLE (-3175 2050);
FORCEPROP 1 LAST PATH I112
J 2
(-2848 2175);
DISPLAY 0.872340 (-2848 2175);
PAINT GREEN (-2848 2175);
DISPLAY INVISIBLE (-2848 2175);
FORCEADD TAP..6
R 2
(-2850 2225);
FORCEPROP 3 LASTPIN (-2900 2225) SIG_NAME M_G_MA<6>
J 0
(-2890 2235);
DISPLAY 0.659574 (-2890 2235);
PAINT MONO (-2890 2235);
DISPLAY INVISIBLE (-2890 2235);
FORCEPROP 1 LASTPIN (-2900 2225) BN 6
J 2
(-2848 2233);
DISPLAY 0.617021 (-2848 2233);
PAINT GREEN (-2848 2233);
FORCEPROP 2 LAST CDS_LIB mstr_standard
J 0
(-2850 2225);
PAINT MONO (-2850 2225);
DISPLAY INVISIBLE (-2850 2225);
FORCEPROP 1 LAST BODY_TYPE PLUMBING
J 2
(-2850 2175);
DISPLAY 1.595745 (-2850 2175);
PAINT GREEN (-2850 2175);
DISPLAY INVISIBLE (-2850 2175);
FORCEPROP 1 LAST HDL_TAP TRUE
J 2
(-3175 2100);
DISPLAY 1.595745 (-3175 2100);
PAINT GREEN (-3175 2100);
DISPLAY INVISIBLE (-3175 2100);
FORCEPROP 1 LAST PATH I113
J 2
(-2848 2225);
DISPLAY 0.872340 (-2848 2225);
PAINT GREEN (-2848 2225);
DISPLAY INVISIBLE (-2848 2225);
FORCEADD TAP..6
R 2
(-2850 2325);
FORCEPROP 3 LASTPIN (-2900 2325) SIG_NAME M_G_MA<8>
J 0
(-2890 2335);
DISPLAY 0.659574 (-2890 2335);
PAINT MONO (-2890 2335);
DISPLAY INVISIBLE (-2890 2335);
FORCEPROP 1 LASTPIN (-2900 2325) BN 8
J 2
(-2848 2333);
DISPLAY 0.617021 (-2848 2333);
PAINT GREEN (-2848 2333);
FORCEPROP 2 LAST CDS_LIB mstr_standard
J 0
(-2850 2325);
PAINT MONO (-2850 2325);
DISPLAY INVISIBLE (-2850 2325);
FORCEPROP 1 LAST BODY_TYPE PLUMBING
J 2
(-2850 2275);
DISPLAY 1.595745 (-2850 2275);
PAINT GREEN (-2850 2275);
DISPLAY INVISIBLE (-2850 2275);
FORCEPROP 1 LAST HDL_TAP TRUE
J 2
(-3175 2200);
DISPLAY 1.595745 (-3175 2200);
PAINT GREEN (-3175 2200);
DISPLAY INVISIBLE (-3175 2200);
FORCEPROP 1 LAST PATH I114
J 2
(-2848 2325);
DISPLAY 0.872340 (-2848 2325);
PAINT GREEN (-2848 2325);
DISPLAY INVISIBLE (-2848 2325);
FORCEADD TAP..6
R 2
(-2850 2275);
FORCEPROP 3 LASTPIN (-2900 2275) SIG_NAME M_G_MA<7>
J 0
(-2890 2285);
DISPLAY 0.659574 (-2890 2285);
PAINT MONO (-2890 2285);
DISPLAY INVISIBLE (-2890 2285);
FORCEPROP 1 LASTPIN (-2900 2275) BN 7
J 2
(-2848 2283);
DISPLAY 0.617021 (-2848 2283);
PAINT GREEN (-2848 2283);
FORCEPROP 2 LAST CDS_LIB mstr_standard
J 0
(-2850 2275);
PAINT MONO (-2850 2275);
DISPLAY INVISIBLE (-2850 2275);
FORCEPROP 1 LAST BODY_TYPE PLUMBING
J 2
(-2850 2225);
DISPLAY 1.595745 (-2850 2225);
PAINT GREEN (-2850 2225);
DISPLAY INVISIBLE (-2850 2225);
FORCEPROP 1 LAST HDL_TAP TRUE
J 2
(-3175 2150);
DISPLAY 1.595745 (-3175 2150);
PAINT GREEN (-3175 2150);
DISPLAY INVISIBLE (-3175 2150);
FORCEPROP 1 LAST PATH I115
J 2
(-2848 2275);
DISPLAY 0.872340 (-2848 2275);
PAINT GREEN (-2848 2275);
DISPLAY INVISIBLE (-2848 2275);
FORCEADD TAP..6
R 2
(-2850 2475);
FORCEPROP 3 LASTPIN (-2900 2475) SIG_NAME M_G_MA<11>
J 0
(-2890 2485);
DISPLAY 0.659574 (-2890 2485);
PAINT MONO (-2890 2485);
DISPLAY INVISIBLE (-2890 2485);
FORCEPROP 1 LASTPIN (-2900 2475) BN 11
J 2
(-2848 2483);
DISPLAY 0.617021 (-2848 2483);
PAINT GREEN (-2848 2483);
FORCEPROP 2 LAST CDS_LIB mstr_standard
J 0
(-2850 2475);
PAINT MONO (-2850 2475);
DISPLAY INVISIBLE (-2850 2475);
FORCEPROP 1 LAST BODY_TYPE PLUMBING
J 2
(-2850 2425);
DISPLAY 1.595745 (-2850 2425);
PAINT GREEN (-2850 2425);
DISPLAY INVISIBLE (-2850 2425);
FORCEPROP 1 LAST HDL_TAP TRUE
J 2
(-3175 2350);
DISPLAY 1.595745 (-3175 2350);
PAINT GREEN (-3175 2350);
DISPLAY INVISIBLE (-3175 2350);
FORCEPROP 1 LAST PATH I116
J 2
(-2848 2475);
DISPLAY 0.872340 (-2848 2475);
PAINT GREEN (-2848 2475);
DISPLAY INVISIBLE (-2848 2475);
FORCEADD TAP..6
R 2
(-2850 2425);
FORCEPROP 3 LASTPIN (-2900 2425) SIG_NAME M_G_MA<10>
J 0
(-2890 2435);
DISPLAY 0.659574 (-2890 2435);
PAINT MONO (-2890 2435);
DISPLAY INVISIBLE (-2890 2435);
FORCEPROP 1 LASTPIN (-2900 2425) BN 10
J 2
(-2848 2433);
DISPLAY 0.617021 (-2848 2433);
PAINT GREEN (-2848 2433);
FORCEPROP 2 LAST CDS_LIB mstr_standard
J 0
(-2850 2425);
PAINT MONO (-2850 2425);
DISPLAY INVISIBLE (-2850 2425);
FORCEPROP 1 LAST BODY_TYPE PLUMBING
J 2
(-2850 2375);
DISPLAY 1.595745 (-2850 2375);
PAINT GREEN (-2850 2375);
DISPLAY INVISIBLE (-2850 2375);
FORCEPROP 1 LAST HDL_TAP TRUE
J 2
(-3175 2300);
DISPLAY 1.595745 (-3175 2300);
PAINT GREEN (-3175 2300);
DISPLAY INVISIBLE (-3175 2300);
FORCEPROP 1 LAST PATH I117
J 2
(-2848 2425);
DISPLAY 0.872340 (-2848 2425);
PAINT GREEN (-2848 2425);
DISPLAY INVISIBLE (-2848 2425);
FORCEADD TAP..6
R 2
(-2850 2375);
FORCEPROP 3 LASTPIN (-2900 2375) SIG_NAME M_G_MA<9>
J 0
(-2890 2385);
DISPLAY 0.659574 (-2890 2385);
PAINT MONO (-2890 2385);
DISPLAY INVISIBLE (-2890 2385);
FORCEPROP 1 LASTPIN (-2900 2375) BN 9
J 2
(-2848 2383);
DISPLAY 0.617021 (-2848 2383);
PAINT GREEN (-2848 2383);
FORCEPROP 2 LAST CDS_LIB mstr_standard
J 0
(-2850 2375);
PAINT MONO (-2850 2375);
DISPLAY INVISIBLE (-2850 2375);
FORCEPROP 1 LAST BODY_TYPE PLUMBING
J 2
(-2850 2325);
DISPLAY 1.595745 (-2850 2325);
PAINT GREEN (-2850 2325);
DISPLAY INVISIBLE (-2850 2325);
FORCEPROP 1 LAST HDL_TAP TRUE
J 2
(-3175 2250);
DISPLAY 1.595745 (-3175 2250);
PAINT GREEN (-3175 2250);
DISPLAY INVISIBLE (-3175 2250);
FORCEPROP 1 LAST PATH I118
J 2
(-2848 2375);
DISPLAY 0.872340 (-2848 2375);
PAINT GREEN (-2848 2375);
DISPLAY INVISIBLE (-2848 2375);
FORCEADD TAP..6
R 2
(-2850 2525);
FORCEPROP 3 LASTPIN (-2900 2525) SIG_NAME M_G_MA<12>
J 0
(-2890 2535);
DISPLAY 0.659574 (-2890 2535);
PAINT MONO (-2890 2535);
DISPLAY INVISIBLE (-2890 2535);
FORCEPROP 1 LASTPIN (-2900 2525) BN 12
J 2
(-2848 2533);
DISPLAY 0.617021 (-2848 2533);
PAINT GREEN (-2848 2533);
FORCEPROP 2 LAST CDS_LIB mstr_standard
J 0
(-2850 2525);
PAINT MONO (-2850 2525);
DISPLAY INVISIBLE (-2850 2525);
FORCEPROP 1 LAST BODY_TYPE PLUMBING
J 2
(-2850 2475);
DISPLAY 1.595745 (-2850 2475);
PAINT GREEN (-2850 2475);
DISPLAY INVISIBLE (-2850 2475);
FORCEPROP 1 LAST HDL_TAP TRUE
J 2
(-3175 2400);
DISPLAY 1.595745 (-3175 2400);
PAINT GREEN (-3175 2400);
DISPLAY INVISIBLE (-3175 2400);
FORCEPROP 1 LAST PATH I119
J 2
(-2848 2525);
DISPLAY 0.872340 (-2848 2525);
PAINT GREEN (-2848 2525);
DISPLAY INVISIBLE (-2848 2525);
FORCEADD TAP..6
(-5575 975);
FORCEPROP 3 LASTPIN (-5525 975) SIG_NAME M_G_CLK_DP<3>
J 0
(-5515 985);
DISPLAY 0.659574 (-5515 985);
PAINT MONO (-5515 985);
DISPLAY INVISIBLE (-5515 985);
FORCEPROP 1 LASTPIN (-5525 975) BN 3
J 0
(-5577 983);
DISPLAY 0.617021 (-5577 983);
PAINT GREEN (-5577 983);
FORCEPROP 2 LAST CDS_LIB mstr_standard
J 0
(-5575 975);
PAINT MONO (-5575 975);
DISPLAY INVISIBLE (-5575 975);
FORCEPROP 1 LAST BODY_TYPE PLUMBING
J 0
(-5575 925);
DISPLAY 1.595745 (-5575 925);
PAINT GREEN (-5575 925);
DISPLAY INVISIBLE (-5575 925);
FORCEPROP 1 LAST HDL_TAP TRUE
J 0
(-5250 850);
DISPLAY 1.595745 (-5250 850);
PAINT GREEN (-5250 850);
DISPLAY INVISIBLE (-5250 850);
FORCEPROP 1 LAST PATH I12
J 0
(-5577 975);
DISPLAY 0.872340 (-5577 975);
PAINT GREEN (-5577 975);
DISPLAY INVISIBLE (-5577 975);
FORCEADD TAP..6
R 2
(-2850 2575);
FORCEPROP 3 LASTPIN (-2900 2575) SIG_NAME M_G_MA<13>
J 0
(-2890 2585);
DISPLAY 0.659574 (-2890 2585);
PAINT MONO (-2890 2585);
DISPLAY INVISIBLE (-2890 2585);
FORCEPROP 1 LASTPIN (-2900 2575) BN 13
J 2
(-2848 2583);
DISPLAY 0.617021 (-2848 2583);
PAINT GREEN (-2848 2583);
FORCEPROP 2 LAST CDS_LIB mstr_standard
J 0
(-2850 2575);
PAINT MONO (-2850 2575);
DISPLAY INVISIBLE (-2850 2575);
FORCEPROP 1 LAST BODY_TYPE PLUMBING
J 2
(-2850 2525);
DISPLAY 1.595745 (-2850 2525);
PAINT GREEN (-2850 2525);
DISPLAY INVISIBLE (-2850 2525);
FORCEPROP 1 LAST HDL_TAP TRUE
J 2
(-3175 2450);
DISPLAY 1.595745 (-3175 2450);
PAINT GREEN (-3175 2450);
DISPLAY INVISIBLE (-3175 2450);
FORCEPROP 1 LAST PATH I120
J 2
(-2848 2575);
DISPLAY 0.872340 (-2848 2575);
PAINT GREEN (-2848 2575);
DISPLAY INVISIBLE (-2848 2575);
FORCEADD TAP..6
R 2
(-2850 2625);
FORCEPROP 3 LASTPIN (-2900 2625) SIG_NAME M_G_MA<14>
J 0
(-2890 2635);
DISPLAY 0.659574 (-2890 2635);
PAINT MONO (-2890 2635);
DISPLAY INVISIBLE (-2890 2635);
FORCEPROP 1 LASTPIN (-2900 2625) BN 14
J 2
(-2848 2633);
DISPLAY 0.617021 (-2848 2633);
PAINT GREEN (-2848 2633);
FORCEPROP 2 LAST CDS_LIB mstr_standard
J 0
(-2850 2625);
PAINT MONO (-2850 2625);
DISPLAY INVISIBLE (-2850 2625);
FORCEPROP 1 LAST BODY_TYPE PLUMBING
J 2
(-2850 2575);
DISPLAY 1.595745 (-2850 2575);
PAINT GREEN (-2850 2575);
DISPLAY INVISIBLE (-2850 2575);
FORCEPROP 1 LAST HDL_TAP TRUE
J 2
(-3175 2500);
DISPLAY 1.595745 (-3175 2500);
PAINT GREEN (-3175 2500);
DISPLAY INVISIBLE (-3175 2500);
FORCEPROP 1 LAST PATH I121
J 2
(-2848 2625);
DISPLAY 0.872340 (-2848 2625);
PAINT GREEN (-2848 2625);
DISPLAY INVISIBLE (-2848 2625);
FORCEADD TAP..6
R 2
(-2850 2675);
FORCEPROP 3 LASTPIN (-2900 2675) SIG_NAME M_G_MA<15>
J 0
(-2890 2685);
DISPLAY 0.659574 (-2890 2685);
PAINT MONO (-2890 2685);
DISPLAY INVISIBLE (-2890 2685);
FORCEPROP 1 LASTPIN (-2900 2675) BN 15
J 2
(-2848 2683);
DISPLAY 0.617021 (-2848 2683);
PAINT GREEN (-2848 2683);
FORCEPROP 2 LAST CDS_LIB mstr_standard
J 0
(-2850 2675);
PAINT MONO (-2850 2675);
DISPLAY INVISIBLE (-2850 2675);
FORCEPROP 1 LAST BODY_TYPE PLUMBING
J 2
(-2850 2625);
DISPLAY 1.595745 (-2850 2625);
PAINT GREEN (-2850 2625);
DISPLAY INVISIBLE (-2850 2625);
FORCEPROP 1 LAST HDL_TAP TRUE
J 2
(-3175 2550);
DISPLAY 1.595745 (-3175 2550);
PAINT GREEN (-3175 2550);
DISPLAY INVISIBLE (-3175 2550);
FORCEPROP 1 LAST PATH I122
J 2
(-2848 2675);
DISPLAY 0.872340 (-2848 2675);
PAINT GREEN (-2848 2675);
DISPLAY INVISIBLE (-2848 2675);
FORCEADD TAP..6
R 2
(-2850 2725);
FORCEPROP 3 LASTPIN (-2900 2725) SIG_NAME M_G_MA<16>
J 0
(-2890 2735);
DISPLAY 0.659574 (-2890 2735);
PAINT MONO (-2890 2735);
DISPLAY INVISIBLE (-2890 2735);
FORCEPROP 1 LASTPIN (-2900 2725) BN 16
J 2
(-2848 2733);
DISPLAY 0.617021 (-2848 2733);
PAINT GREEN (-2848 2733);
FORCEPROP 2 LAST CDS_LIB mstr_standard
J 0
(-2850 2725);
PAINT MONO (-2850 2725);
DISPLAY INVISIBLE (-2850 2725);
FORCEPROP 1 LAST BODY_TYPE PLUMBING
J 2
(-2850 2675);
DISPLAY 1.595745 (-2850 2675);
PAINT GREEN (-2850 2675);
DISPLAY INVISIBLE (-2850 2675);
FORCEPROP 1 LAST HDL_TAP TRUE
J 2
(-3175 2600);
DISPLAY 1.595745 (-3175 2600);
PAINT GREEN (-3175 2600);
DISPLAY INVISIBLE (-3175 2600);
FORCEPROP 1 LAST PATH I123
J 2
(-2848 2725);
DISPLAY 0.872340 (-2848 2725);
PAINT GREEN (-2848 2725);
DISPLAY INVISIBLE (-2848 2725);
FORCEADD TAP..6
R 2
(-2850 2775);
FORCEPROP 3 LASTPIN (-2900 2775) SIG_NAME M_G_MA<17>
J 0
(-2890 2785);
DISPLAY 0.659574 (-2890 2785);
PAINT MONO (-2890 2785);
DISPLAY INVISIBLE (-2890 2785);
FORCEPROP 1 LASTPIN (-2900 2775) BN 17
J 2
(-2848 2783);
DISPLAY 0.617021 (-2848 2783);
PAINT GREEN (-2848 2783);
FORCEPROP 2 LAST CDS_LIB mstr_standard
J 0
(-2850 2775);
PAINT MONO (-2850 2775);
DISPLAY INVISIBLE (-2850 2775);
FORCEPROP 1 LAST BODY_TYPE PLUMBING
J 2
(-2850 2725);
DISPLAY 1.595745 (-2850 2725);
PAINT GREEN (-2850 2725);
DISPLAY INVISIBLE (-2850 2725);
FORCEPROP 1 LAST HDL_TAP TRUE
J 2
(-3175 2650);
DISPLAY 1.595745 (-3175 2650);
PAINT GREEN (-3175 2650);
DISPLAY INVISIBLE (-3175 2650);
FORCEPROP 1 LAST PATH I124
J 2
(-2848 2775);
DISPLAY 0.872340 (-2848 2775);
PAINT GREEN (-2848 2775);
DISPLAY INVISIBLE (-2848 2775);
FORCEADD TAP..6
R 2
(-2850 2925);
FORCEPROP 3 LASTPIN (-2900 2925) SIG_NAME M_G_DQS_DN<1>
J 0
(-2890 2935);
DISPLAY 0.659574 (-2890 2935);
PAINT MONO (-2890 2935);
DISPLAY INVISIBLE (-2890 2935);
FORCEPROP 1 LASTPIN (-2900 2925) BN 1
J 2
(-2848 2933);
DISPLAY 0.617021 (-2848 2933);
PAINT GREEN (-2848 2933);
FORCEPROP 2 LAST CDS_LIB mstr_standard
J 0
(-2850 2925);
PAINT MONO (-2850 2925);
DISPLAY INVISIBLE (-2850 2925);
FORCEPROP 1 LAST BODY_TYPE PLUMBING
J 2
(-2850 2875);
DISPLAY 1.595745 (-2850 2875);
PAINT GREEN (-2850 2875);
DISPLAY INVISIBLE (-2850 2875);
FORCEPROP 1 LAST HDL_TAP TRUE
J 2
(-3175 2800);
DISPLAY 1.595745 (-3175 2800);
PAINT GREEN (-3175 2800);
DISPLAY INVISIBLE (-3175 2800);
FORCEPROP 1 LAST PATH I125
J 2
(-2848 2925);
DISPLAY 0.872340 (-2848 2925);
PAINT GREEN (-2848 2925);
DISPLAY INVISIBLE (-2848 2925);
FORCEADD TAP..6
R 2
(-2850 2975);
FORCEPROP 3 LASTPIN (-2900 2975) SIG_NAME M_G_DQS_DN<2>
J 0
(-2890 2985);
DISPLAY 0.659574 (-2890 2985);
PAINT MONO (-2890 2985);
DISPLAY INVISIBLE (-2890 2985);
FORCEPROP 1 LASTPIN (-2900 2975) BN 2
J 2
(-2848 2983);
DISPLAY 0.617021 (-2848 2983);
PAINT GREEN (-2848 2983);
FORCEPROP 2 LAST CDS_LIB mstr_standard
J 0
(-2850 2975);
PAINT MONO (-2850 2975);
DISPLAY INVISIBLE (-2850 2975);
FORCEPROP 1 LAST BODY_TYPE PLUMBING
J 2
(-2850 2925);
DISPLAY 1.595745 (-2850 2925);
PAINT GREEN (-2850 2925);
DISPLAY INVISIBLE (-2850 2925);
FORCEPROP 1 LAST HDL_TAP TRUE
J 2
(-3175 2850);
DISPLAY 1.595745 (-3175 2850);
PAINT GREEN (-3175 2850);
DISPLAY INVISIBLE (-3175 2850);
FORCEPROP 1 LAST PATH I126
J 2
(-2848 2975);
DISPLAY 0.872340 (-2848 2975);
PAINT GREEN (-2848 2975);
DISPLAY INVISIBLE (-2848 2975);
FORCEADD TAP..6
R 2
(-2850 2875);
FORCEPROP 3 LASTPIN (-2900 2875) SIG_NAME M_G_DQS_DN<0>
J 0
(-2890 2885);
DISPLAY 0.659574 (-2890 2885);
PAINT MONO (-2890 2885);
DISPLAY INVISIBLE (-2890 2885);
FORCEPROP 1 LASTPIN (-2900 2875) BN 0
J 2
(-2848 2883);
DISPLAY 0.617021 (-2848 2883);
PAINT GREEN (-2848 2883);
FORCEPROP 2 LAST CDS_LIB mstr_standard
J 0
(-2850 2875);
PAINT MONO (-2850 2875);
DISPLAY INVISIBLE (-2850 2875);
FORCEPROP 1 LAST BODY_TYPE PLUMBING
J 2
(-2850 2825);
DISPLAY 1.595745 (-2850 2825);
PAINT GREEN (-2850 2825);
DISPLAY INVISIBLE (-2850 2825);
FORCEPROP 1 LAST HDL_TAP TRUE
J 2
(-3175 2750);
DISPLAY 1.595745 (-3175 2750);
PAINT GREEN (-3175 2750);
DISPLAY INVISIBLE (-3175 2750);
FORCEPROP 1 LAST PATH I127
J 2
(-2848 2875);
DISPLAY 0.872340 (-2848 2875);
PAINT GREEN (-2848 2875);
DISPLAY INVISIBLE (-2848 2875);
FORCEADD TAP..6
R 2
(-2850 3075);
FORCEPROP 3 LASTPIN (-2900 3075) SIG_NAME M_G_DQS_DN<4>
J 0
(-2890 3085);
DISPLAY 0.659574 (-2890 3085);
PAINT MONO (-2890 3085);
DISPLAY INVISIBLE (-2890 3085);
FORCEPROP 1 LASTPIN (-2900 3075) BN 4
J 2
(-2848 3083);
DISPLAY 0.617021 (-2848 3083);
PAINT GREEN (-2848 3083);
FORCEPROP 2 LAST CDS_LIB mstr_standard
J 0
(-2850 3075);
PAINT MONO (-2850 3075);
DISPLAY INVISIBLE (-2850 3075);
FORCEPROP 1 LAST BODY_TYPE PLUMBING
J 2
(-2850 3025);
DISPLAY 1.595745 (-2850 3025);
PAINT GREEN (-2850 3025);
DISPLAY INVISIBLE (-2850 3025);
FORCEPROP 1 LAST HDL_TAP TRUE
J 2
(-3175 2950);
DISPLAY 1.595745 (-3175 2950);
PAINT GREEN (-3175 2950);
DISPLAY INVISIBLE (-3175 2950);
FORCEPROP 1 LAST PATH I128
J 2
(-2848 3075);
DISPLAY 0.872340 (-2848 3075);
PAINT GREEN (-2848 3075);
DISPLAY INVISIBLE (-2848 3075);
FORCEADD TAP..6
R 2
(-2850 3025);
FORCEPROP 3 LASTPIN (-2900 3025) SIG_NAME M_G_DQS_DN<3>
J 0
(-2890 3035);
DISPLAY 0.659574 (-2890 3035);
PAINT MONO (-2890 3035);
DISPLAY INVISIBLE (-2890 3035);
FORCEPROP 1 LASTPIN (-2900 3025) BN 3
J 2
(-2848 3033);
DISPLAY 0.617021 (-2848 3033);
PAINT GREEN (-2848 3033);
FORCEPROP 2 LAST CDS_LIB mstr_standard
J 0
(-2850 3025);
PAINT MONO (-2850 3025);
DISPLAY INVISIBLE (-2850 3025);
FORCEPROP 1 LAST BODY_TYPE PLUMBING
J 2
(-2850 2975);
DISPLAY 1.595745 (-2850 2975);
PAINT GREEN (-2850 2975);
DISPLAY INVISIBLE (-2850 2975);
FORCEPROP 1 LAST HDL_TAP TRUE
J 2
(-3175 2900);
DISPLAY 1.595745 (-3175 2900);
PAINT GREEN (-3175 2900);
DISPLAY INVISIBLE (-3175 2900);
FORCEPROP 1 LAST PATH I129
J 2
(-2848 3025);
DISPLAY 0.872340 (-2848 3025);
PAINT GREEN (-2848 3025);
DISPLAY INVISIBLE (-2848 3025);
FORCEADD TAP..6
(-5575 1075);
FORCEPROP 3 LASTPIN (-5525 1075) SIG_NAME M_G_ECC<0>
J 0
(-5515 1085);
DISPLAY 0.659574 (-5515 1085);
PAINT MONO (-5515 1085);
DISPLAY INVISIBLE (-5515 1085);
FORCEPROP 1 LASTPIN (-5525 1075) BN 0
J 0
(-5577 1083);
DISPLAY 0.617021 (-5577 1083);
PAINT GREEN (-5577 1083);
FORCEPROP 2 LAST CDS_LIB mstr_standard
J 0
(-5575 1075);
PAINT MONO (-5575 1075);
DISPLAY INVISIBLE (-5575 1075);
FORCEPROP 1 LAST BODY_TYPE PLUMBING
J 0
(-5575 1025);
DISPLAY 1.595745 (-5575 1025);
PAINT GREEN (-5575 1025);
DISPLAY INVISIBLE (-5575 1025);
FORCEPROP 1 LAST HDL_TAP TRUE
J 0
(-5250 950);
DISPLAY 1.595745 (-5250 950);
PAINT GREEN (-5250 950);
DISPLAY INVISIBLE (-5250 950);
FORCEPROP 1 LAST PATH I13
J 0
(-5577 1075);
DISPLAY 0.872340 (-5577 1075);
PAINT GREEN (-5577 1075);
DISPLAY INVISIBLE (-5577 1075);
FORCEADD TAP..6
R 2
(-2850 3125);
FORCEPROP 3 LASTPIN (-2900 3125) SIG_NAME M_G_DQS_DN<5>
J 0
(-2890 3135);
DISPLAY 0.659574 (-2890 3135);
PAINT MONO (-2890 3135);
DISPLAY INVISIBLE (-2890 3135);
FORCEPROP 1 LASTPIN (-2900 3125) BN 5
J 2
(-2848 3133);
DISPLAY 0.617021 (-2848 3133);
PAINT GREEN (-2848 3133);
FORCEPROP 2 LAST CDS_LIB mstr_standard
J 0
(-2850 3125);
PAINT MONO (-2850 3125);
DISPLAY INVISIBLE (-2850 3125);
FORCEPROP 1 LAST BODY_TYPE PLUMBING
J 2
(-2850 3075);
DISPLAY 1.595745 (-2850 3075);
PAINT GREEN (-2850 3075);
DISPLAY INVISIBLE (-2850 3075);
FORCEPROP 1 LAST HDL_TAP TRUE
J 2
(-3175 3000);
DISPLAY 1.595745 (-3175 3000);
PAINT GREEN (-3175 3000);
DISPLAY INVISIBLE (-3175 3000);
FORCEPROP 1 LAST PATH I130
J 2
(-2848 3125);
DISPLAY 0.872340 (-2848 3125);
PAINT GREEN (-2848 3125);
DISPLAY INVISIBLE (-2848 3125);
FORCEADD TAP..6
R 2
(-2850 3175);
FORCEPROP 3 LASTPIN (-2900 3175) SIG_NAME M_G_DQS_DN<6>
J 0
(-2890 3185);
DISPLAY 0.659574 (-2890 3185);
PAINT MONO (-2890 3185);
DISPLAY INVISIBLE (-2890 3185);
FORCEPROP 1 LASTPIN (-2900 3175) BN 6
J 2
(-2848 3183);
DISPLAY 0.617021 (-2848 3183);
PAINT GREEN (-2848 3183);
FORCEPROP 2 LAST CDS_LIB mstr_standard
J 0
(-2850 3175);
PAINT MONO (-2850 3175);
DISPLAY INVISIBLE (-2850 3175);
FORCEPROP 1 LAST BODY_TYPE PLUMBING
J 2
(-2850 3125);
DISPLAY 1.595745 (-2850 3125);
PAINT GREEN (-2850 3125);
DISPLAY INVISIBLE (-2850 3125);
FORCEPROP 1 LAST HDL_TAP TRUE
J 2
(-3175 3050);
DISPLAY 1.595745 (-3175 3050);
PAINT GREEN (-3175 3050);
DISPLAY INVISIBLE (-3175 3050);
FORCEPROP 1 LAST PATH I131
J 2
(-2848 3175);
DISPLAY 0.872340 (-2848 3175);
PAINT GREEN (-2848 3175);
DISPLAY INVISIBLE (-2848 3175);
FORCEADD TAP..6
R 2
(-2850 3225);
FORCEPROP 3 LASTPIN (-2900 3225) SIG_NAME M_G_DQS_DN<7>
J 0
(-2890 3235);
DISPLAY 0.659574 (-2890 3235);
PAINT MONO (-2890 3235);
DISPLAY INVISIBLE (-2890 3235);
FORCEPROP 1 LASTPIN (-2900 3225) BN 7
J 2
(-2848 3233);
DISPLAY 0.617021 (-2848 3233);
PAINT GREEN (-2848 3233);
FORCEPROP 2 LAST CDS_LIB mstr_standard
J 0
(-2850 3225);
PAINT MONO (-2850 3225);
DISPLAY INVISIBLE (-2850 3225);
FORCEPROP 1 LAST BODY_TYPE PLUMBING
J 2
(-2850 3175);
DISPLAY 1.595745 (-2850 3175);
PAINT GREEN (-2850 3175);
DISPLAY INVISIBLE (-2850 3175);
FORCEPROP 1 LAST HDL_TAP TRUE
J 2
(-3175 3100);
DISPLAY 1.595745 (-3175 3100);
PAINT GREEN (-3175 3100);
DISPLAY INVISIBLE (-3175 3100);
FORCEPROP 1 LAST PATH I132
J 2
(-2848 3225);
DISPLAY 0.872340 (-2848 3225);
PAINT GREEN (-2848 3225);
DISPLAY INVISIBLE (-2848 3225);
FORCEADD TAP..6
R 2
(-2850 3275);
FORCEPROP 3 LASTPIN (-2900 3275) SIG_NAME M_G_DQS_DN<8>
J 0
(-2890 3285);
DISPLAY 0.659574 (-2890 3285);
PAINT MONO (-2890 3285);
DISPLAY INVISIBLE (-2890 3285);
FORCEPROP 1 LASTPIN (-2900 3275) BN 8
J 2
(-2848 3283);
DISPLAY 0.617021 (-2848 3283);
PAINT GREEN (-2848 3283);
FORCEPROP 2 LAST CDS_LIB mstr_standard
J 0
(-2850 3275);
PAINT MONO (-2850 3275);
DISPLAY INVISIBLE (-2850 3275);
FORCEPROP 1 LAST BODY_TYPE PLUMBING
J 2
(-2850 3225);
DISPLAY 1.595745 (-2850 3225);
PAINT GREEN (-2850 3225);
DISPLAY INVISIBLE (-2850 3225);
FORCEPROP 1 LAST HDL_TAP TRUE
J 2
(-3175 3150);
DISPLAY 1.595745 (-3175 3150);
PAINT GREEN (-3175 3150);
DISPLAY INVISIBLE (-3175 3150);
FORCEPROP 1 LAST PATH I133
J 2
(-2848 3275);
DISPLAY 0.872340 (-2848 3275);
PAINT GREEN (-2848 3275);
DISPLAY INVISIBLE (-2848 3275);
FORCEADD TAP..6
R 2
(-2850 3325);
FORCEPROP 3 LASTPIN (-2900 3325) SIG_NAME M_G_DQS_DN<9>
J 0
(-2890 3335);
DISPLAY 0.659574 (-2890 3335);
PAINT MONO (-2890 3335);
DISPLAY INVISIBLE (-2890 3335);
FORCEPROP 1 LASTPIN (-2900 3325) BN 9
J 2
(-2848 3333);
DISPLAY 0.617021 (-2848 3333);
PAINT GREEN (-2848 3333);
FORCEPROP 2 LAST CDS_LIB mstr_standard
J 0
(-2850 3325);
PAINT MONO (-2850 3325);
DISPLAY INVISIBLE (-2850 3325);
FORCEPROP 1 LAST BODY_TYPE PLUMBING
J 2
(-2850 3275);
DISPLAY 1.595745 (-2850 3275);
PAINT GREEN (-2850 3275);
DISPLAY INVISIBLE (-2850 3275);
FORCEPROP 1 LAST HDL_TAP TRUE
J 2
(-3175 3200);
DISPLAY 1.595745 (-3175 3200);
PAINT GREEN (-3175 3200);
DISPLAY INVISIBLE (-3175 3200);
FORCEPROP 1 LAST PATH I134
J 2
(-2848 3325);
DISPLAY 0.872340 (-2848 3325);
PAINT GREEN (-2848 3325);
DISPLAY INVISIBLE (-2848 3325);
FORCEADD TAP..6
R 2
(-2850 3375);
FORCEPROP 3 LASTPIN (-2900 3375) SIG_NAME M_G_DQS_DN<10>
J 0
(-2890 3385);
DISPLAY 0.659574 (-2890 3385);
PAINT MONO (-2890 3385);
DISPLAY INVISIBLE (-2890 3385);
FORCEPROP 1 LASTPIN (-2900 3375) BN 10
J 2
(-2848 3383);
DISPLAY 0.617021 (-2848 3383);
PAINT GREEN (-2848 3383);
FORCEPROP 2 LAST CDS_LIB mstr_standard
J 0
(-2850 3375);
PAINT MONO (-2850 3375);
DISPLAY INVISIBLE (-2850 3375);
FORCEPROP 1 LAST BODY_TYPE PLUMBING
J 2
(-2850 3325);
DISPLAY 1.595745 (-2850 3325);
PAINT GREEN (-2850 3325);
DISPLAY INVISIBLE (-2850 3325);
FORCEPROP 1 LAST HDL_TAP TRUE
J 2
(-3175 3250);
DISPLAY 1.595745 (-3175 3250);
PAINT GREEN (-3175 3250);
DISPLAY INVISIBLE (-3175 3250);
FORCEPROP 1 LAST PATH I135
J 2
(-2848 3375);
DISPLAY 0.872340 (-2848 3375);
PAINT GREEN (-2848 3375);
DISPLAY INVISIBLE (-2848 3375);
FORCEADD TAP..6
R 2
(-2850 3475);
FORCEPROP 3 LASTPIN (-2900 3475) SIG_NAME M_G_DQS_DN<12>
J 0
(-2890 3485);
DISPLAY 0.659574 (-2890 3485);
PAINT MONO (-2890 3485);
DISPLAY INVISIBLE (-2890 3485);
FORCEPROP 1 LASTPIN (-2900 3475) BN 12
J 2
(-2848 3483);
DISPLAY 0.617021 (-2848 3483);
PAINT GREEN (-2848 3483);
FORCEPROP 2 LAST CDS_LIB mstr_standard
J 0
(-2850 3475);
PAINT MONO (-2850 3475);
DISPLAY INVISIBLE (-2850 3475);
FORCEPROP 1 LAST BODY_TYPE PLUMBING
J 2
(-2850 3425);
DISPLAY 1.595745 (-2850 3425);
PAINT GREEN (-2850 3425);
DISPLAY INVISIBLE (-2850 3425);
FORCEPROP 1 LAST HDL_TAP TRUE
J 2
(-3175 3350);
DISPLAY 1.595745 (-3175 3350);
PAINT GREEN (-3175 3350);
DISPLAY INVISIBLE (-3175 3350);
FORCEPROP 1 LAST PATH I136
J 2
(-2848 3475);
DISPLAY 0.872340 (-2848 3475);
PAINT GREEN (-2848 3475);
DISPLAY INVISIBLE (-2848 3475);
FORCEADD TAP..6
R 2
(-2850 3425);
FORCEPROP 3 LASTPIN (-2900 3425) SIG_NAME M_G_DQS_DN<11>
J 0
(-2890 3435);
DISPLAY 0.659574 (-2890 3435);
PAINT MONO (-2890 3435);
DISPLAY INVISIBLE (-2890 3435);
FORCEPROP 1 LASTPIN (-2900 3425) BN 11
J 2
(-2848 3433);
DISPLAY 0.617021 (-2848 3433);
PAINT GREEN (-2848 3433);
FORCEPROP 2 LAST CDS_LIB mstr_standard
J 0
(-2850 3425);
PAINT MONO (-2850 3425);
DISPLAY INVISIBLE (-2850 3425);
FORCEPROP 1 LAST BODY_TYPE PLUMBING
J 2
(-2850 3375);
DISPLAY 1.595745 (-2850 3375);
PAINT GREEN (-2850 3375);
DISPLAY INVISIBLE (-2850 3375);
FORCEPROP 1 LAST HDL_TAP TRUE
J 2
(-3175 3300);
DISPLAY 1.595745 (-3175 3300);
PAINT GREEN (-3175 3300);
DISPLAY INVISIBLE (-3175 3300);
FORCEPROP 1 LAST PATH I137
J 2
(-2848 3425);
DISPLAY 0.872340 (-2848 3425);
PAINT GREEN (-2848 3425);
DISPLAY INVISIBLE (-2848 3425);
FORCEADD TAP..6
R 2
(-2850 3625);
FORCEPROP 3 LASTPIN (-2900 3625) SIG_NAME M_G_DQS_DN<15>
J 0
(-2890 3635);
DISPLAY 0.659574 (-2890 3635);
PAINT MONO (-2890 3635);
DISPLAY INVISIBLE (-2890 3635);
FORCEPROP 1 LASTPIN (-2900 3625) BN 15
J 2
(-2848 3633);
DISPLAY 0.617021 (-2848 3633);
PAINT GREEN (-2848 3633);
FORCEPROP 2 LAST CDS_LIB mstr_standard
J 0
(-2850 3625);
PAINT MONO (-2850 3625);
DISPLAY INVISIBLE (-2850 3625);
FORCEPROP 1 LAST BODY_TYPE PLUMBING
J 2
(-2850 3575);
DISPLAY 1.595745 (-2850 3575);
PAINT GREEN (-2850 3575);
DISPLAY INVISIBLE (-2850 3575);
FORCEPROP 1 LAST HDL_TAP TRUE
J 2
(-3175 3500);
DISPLAY 1.595745 (-3175 3500);
PAINT GREEN (-3175 3500);
DISPLAY INVISIBLE (-3175 3500);
FORCEPROP 1 LAST PATH I138
J 2
(-2848 3625);
DISPLAY 0.872340 (-2848 3625);
PAINT GREEN (-2848 3625);
DISPLAY INVISIBLE (-2848 3625);
FORCEADD TAP..6
R 2
(-2850 3575);
FORCEPROP 3 LASTPIN (-2900 3575) SIG_NAME M_G_DQS_DN<14>
J 0
(-2890 3585);
DISPLAY 0.659574 (-2890 3585);
PAINT MONO (-2890 3585);
DISPLAY INVISIBLE (-2890 3585);
FORCEPROP 1 LASTPIN (-2900 3575) BN 14
J 2
(-2848 3583);
DISPLAY 0.617021 (-2848 3583);
PAINT GREEN (-2848 3583);
FORCEPROP 2 LAST CDS_LIB mstr_standard
J 0
(-2850 3575);
PAINT MONO (-2850 3575);
DISPLAY INVISIBLE (-2850 3575);
FORCEPROP 1 LAST BODY_TYPE PLUMBING
J 2
(-2850 3525);
DISPLAY 1.595745 (-2850 3525);
PAINT GREEN (-2850 3525);
DISPLAY INVISIBLE (-2850 3525);
FORCEPROP 1 LAST HDL_TAP TRUE
J 2
(-3175 3450);
DISPLAY 1.595745 (-3175 3450);
PAINT GREEN (-3175 3450);
DISPLAY INVISIBLE (-3175 3450);
FORCEPROP 1 LAST PATH I139
J 2
(-2848 3575);
DISPLAY 0.872340 (-2848 3575);
PAINT GREEN (-2848 3575);
DISPLAY INVISIBLE (-2848 3575);
FORCEADD TAP..6
(-5575 1125);
FORCEPROP 3 LASTPIN (-5525 1125) SIG_NAME M_G_ECC<1>
J 0
(-5515 1135);
DISPLAY 0.659574 (-5515 1135);
PAINT MONO (-5515 1135);
DISPLAY INVISIBLE (-5515 1135);
FORCEPROP 1 LASTPIN (-5525 1125) BN 1
J 0
(-5577 1133);
DISPLAY 0.617021 (-5577 1133);
PAINT GREEN (-5577 1133);
FORCEPROP 2 LAST CDS_LIB mstr_standard
J 0
(-5575 1125);
PAINT MONO (-5575 1125);
DISPLAY INVISIBLE (-5575 1125);
FORCEPROP 1 LAST BODY_TYPE PLUMBING
J 0
(-5575 1075);
DISPLAY 1.595745 (-5575 1075);
PAINT GREEN (-5575 1075);
DISPLAY INVISIBLE (-5575 1075);
FORCEPROP 1 LAST HDL_TAP TRUE
J 0
(-5250 1000);
DISPLAY 1.595745 (-5250 1000);
PAINT GREEN (-5250 1000);
DISPLAY INVISIBLE (-5250 1000);
FORCEPROP 1 LAST PATH I14
J 0
(-5577 1125);
DISPLAY 0.872340 (-5577 1125);
PAINT GREEN (-5577 1125);
DISPLAY INVISIBLE (-5577 1125);
FORCEADD TAP..6
R 2
(-2850 3525);
FORCEPROP 3 LASTPIN (-2900 3525) SIG_NAME M_G_DQS_DN<13>
J 0
(-2890 3535);
DISPLAY 0.659574 (-2890 3535);
PAINT MONO (-2890 3535);
DISPLAY INVISIBLE (-2890 3535);
FORCEPROP 1 LASTPIN (-2900 3525) BN 13
J 2
(-2848 3533);
DISPLAY 0.617021 (-2848 3533);
PAINT GREEN (-2848 3533);
FORCEPROP 2 LAST CDS_LIB mstr_standard
J 0
(-2850 3525);
PAINT MONO (-2850 3525);
DISPLAY INVISIBLE (-2850 3525);
FORCEPROP 1 LAST BODY_TYPE PLUMBING
J 2
(-2850 3475);
DISPLAY 1.595745 (-2850 3475);
PAINT GREEN (-2850 3475);
DISPLAY INVISIBLE (-2850 3475);
FORCEPROP 1 LAST HDL_TAP TRUE
J 2
(-3175 3400);
DISPLAY 1.595745 (-3175 3400);
PAINT GREEN (-3175 3400);
DISPLAY INVISIBLE (-3175 3400);
FORCEPROP 1 LAST PATH I140
J 2
(-2848 3525);
DISPLAY 0.872340 (-2848 3525);
PAINT GREEN (-2848 3525);
DISPLAY INVISIBLE (-2848 3525);
FORCEADD TAP..6
R 2
(-2850 3675);
FORCEPROP 3 LASTPIN (-2900 3675) SIG_NAME M_G_DQS_DN<16>
J 0
(-2890 3685);
DISPLAY 0.659574 (-2890 3685);
PAINT MONO (-2890 3685);
DISPLAY INVISIBLE (-2890 3685);
FORCEPROP 1 LASTPIN (-2900 3675) BN 16
J 2
(-2848 3683);
DISPLAY 0.617021 (-2848 3683);
PAINT GREEN (-2848 3683);
FORCEPROP 2 LAST CDS_LIB mstr_standard
J 0
(-2850 3675);
PAINT MONO (-2850 3675);
DISPLAY INVISIBLE (-2850 3675);
FORCEPROP 1 LAST BODY_TYPE PLUMBING
J 2
(-2850 3625);
DISPLAY 1.595745 (-2850 3625);
PAINT GREEN (-2850 3625);
DISPLAY INVISIBLE (-2850 3625);
FORCEPROP 1 LAST HDL_TAP TRUE
J 2
(-3175 3550);
DISPLAY 1.595745 (-3175 3550);
PAINT GREEN (-3175 3550);
DISPLAY INVISIBLE (-3175 3550);
FORCEPROP 1 LAST PATH I141
J 2
(-2848 3675);
DISPLAY 0.872340 (-2848 3675);
PAINT GREEN (-2848 3675);
DISPLAY INVISIBLE (-2848 3675);
FORCEADD TAP..6
R 2
(-2850 3725);
FORCEPROP 3 LASTPIN (-2900 3725) SIG_NAME M_G_DQS_DN<17>
J 0
(-2890 3735);
DISPLAY 0.659574 (-2890 3735);
PAINT MONO (-2890 3735);
DISPLAY INVISIBLE (-2890 3735);
FORCEPROP 1 LASTPIN (-2900 3725) BN 17
J 2
(-2848 3733);
DISPLAY 0.617021 (-2848 3733);
PAINT GREEN (-2848 3733);
FORCEPROP 2 LAST CDS_LIB mstr_standard
J 0
(-2850 3725);
PAINT MONO (-2850 3725);
DISPLAY INVISIBLE (-2850 3725);
FORCEPROP 1 LAST BODY_TYPE PLUMBING
J 2
(-2850 3675);
DISPLAY 1.595745 (-2850 3675);
PAINT GREEN (-2850 3675);
DISPLAY INVISIBLE (-2850 3675);
FORCEPROP 1 LAST HDL_TAP TRUE
J 2
(-3175 3600);
DISPLAY 1.595745 (-3175 3600);
PAINT GREEN (-3175 3600);
DISPLAY INVISIBLE (-3175 3600);
FORCEPROP 1 LAST PATH I142
J 2
(-2848 3725);
DISPLAY 0.872340 (-2848 3725);
PAINT GREEN (-2848 3725);
DISPLAY INVISIBLE (-2848 3725);
FORCEADD TAP..6
R 2
(-2850 3825);
FORCEPROP 3 LASTPIN (-2900 3825) SIG_NAME M_G_DQS_DP<0>
J 0
(-2890 3835);
DISPLAY 0.659574 (-2890 3835);
PAINT MONO (-2890 3835);
DISPLAY INVISIBLE (-2890 3835);
FORCEPROP 1 LASTPIN (-2900 3825) BN 0
J 2
(-2848 3833);
DISPLAY 0.617021 (-2848 3833);
PAINT GREEN (-2848 3833);
FORCEPROP 2 LAST CDS_LIB mstr_standard
J 0
(-2850 3825);
PAINT MONO (-2850 3825);
DISPLAY INVISIBLE (-2850 3825);
FORCEPROP 1 LAST BODY_TYPE PLUMBING
J 2
(-2850 3775);
DISPLAY 1.595745 (-2850 3775);
PAINT GREEN (-2850 3775);
DISPLAY INVISIBLE (-2850 3775);
FORCEPROP 1 LAST HDL_TAP TRUE
J 2
(-3175 3700);
DISPLAY 1.595745 (-3175 3700);
PAINT GREEN (-3175 3700);
DISPLAY INVISIBLE (-3175 3700);
FORCEPROP 1 LAST PATH I143
J 2
(-2848 3825);
DISPLAY 0.872340 (-2848 3825);
PAINT GREEN (-2848 3825);
DISPLAY INVISIBLE (-2848 3825);
FORCEADD TAP..6
R 2
(-2850 3875);
FORCEPROP 3 LASTPIN (-2900 3875) SIG_NAME M_G_DQS_DP<1>
J 0
(-2890 3885);
DISPLAY 0.659574 (-2890 3885);
PAINT MONO (-2890 3885);
DISPLAY INVISIBLE (-2890 3885);
FORCEPROP 1 LASTPIN (-2900 3875) BN 1
J 2
(-2848 3883);
DISPLAY 0.617021 (-2848 3883);
PAINT GREEN (-2848 3883);
FORCEPROP 2 LAST CDS_LIB mstr_standard
J 0
(-2850 3875);
PAINT MONO (-2850 3875);
DISPLAY INVISIBLE (-2850 3875);
FORCEPROP 1 LAST BODY_TYPE PLUMBING
J 2
(-2850 3825);
DISPLAY 1.595745 (-2850 3825);
PAINT GREEN (-2850 3825);
DISPLAY INVISIBLE (-2850 3825);
FORCEPROP 1 LAST HDL_TAP TRUE
J 2
(-3175 3750);
DISPLAY 1.595745 (-3175 3750);
PAINT GREEN (-3175 3750);
DISPLAY INVISIBLE (-3175 3750);
FORCEPROP 1 LAST PATH I144
J 2
(-2848 3875);
DISPLAY 0.872340 (-2848 3875);
PAINT GREEN (-2848 3875);
DISPLAY INVISIBLE (-2848 3875);
FORCEADD TAP..6
R 2
(-2850 3925);
FORCEPROP 3 LASTPIN (-2900 3925) SIG_NAME M_G_DQS_DP<2>
J 0
(-2890 3935);
DISPLAY 0.659574 (-2890 3935);
PAINT MONO (-2890 3935);
DISPLAY INVISIBLE (-2890 3935);
FORCEPROP 1 LASTPIN (-2900 3925) BN 2
J 2
(-2848 3933);
DISPLAY 0.617021 (-2848 3933);
PAINT GREEN (-2848 3933);
FORCEPROP 2 LAST CDS_LIB mstr_standard
J 0
(-2850 3925);
PAINT MONO (-2850 3925);
DISPLAY INVISIBLE (-2850 3925);
FORCEPROP 1 LAST BODY_TYPE PLUMBING
J 2
(-2850 3875);
DISPLAY 1.595745 (-2850 3875);
PAINT GREEN (-2850 3875);
DISPLAY INVISIBLE (-2850 3875);
FORCEPROP 1 LAST HDL_TAP TRUE
J 2
(-3175 3800);
DISPLAY 1.595745 (-3175 3800);
PAINT GREEN (-3175 3800);
DISPLAY INVISIBLE (-3175 3800);
FORCEPROP 1 LAST PATH I145
J 2
(-2848 3925);
DISPLAY 0.872340 (-2848 3925);
PAINT GREEN (-2848 3925);
DISPLAY INVISIBLE (-2848 3925);
FORCEADD TAP..6
R 2
(-2850 3975);
FORCEPROP 3 LASTPIN (-2900 3975) SIG_NAME M_G_DQS_DP<3>
J 0
(-2890 3985);
DISPLAY 0.659574 (-2890 3985);
PAINT MONO (-2890 3985);
DISPLAY INVISIBLE (-2890 3985);
FORCEPROP 1 LASTPIN (-2900 3975) BN 3
J 2
(-2848 3983);
DISPLAY 0.617021 (-2848 3983);
PAINT GREEN (-2848 3983);
FORCEPROP 2 LAST CDS_LIB mstr_standard
J 0
(-2850 3975);
PAINT MONO (-2850 3975);
DISPLAY INVISIBLE (-2850 3975);
FORCEPROP 1 LAST BODY_TYPE PLUMBING
J 2
(-2850 3925);
DISPLAY 1.595745 (-2850 3925);
PAINT GREEN (-2850 3925);
DISPLAY INVISIBLE (-2850 3925);
FORCEPROP 1 LAST HDL_TAP TRUE
J 2
(-3175 3850);
DISPLAY 1.595745 (-3175 3850);
PAINT GREEN (-3175 3850);
DISPLAY INVISIBLE (-3175 3850);
FORCEPROP 1 LAST PATH I146
J 2
(-2848 3975);
DISPLAY 0.872340 (-2848 3975);
PAINT GREEN (-2848 3975);
DISPLAY INVISIBLE (-2848 3975);
FORCEADD OFFPAGE..2
(-2000 525);
FORCEPROP 2 LAST $XR0 77 
J 0
(-1811 525);
DISPLAY 0.638298 (-1811 525);
PAINT MONO (-1811 525);
FORCEPROP 2 LAST $XR1 78 
J 0
(-1721 525);
DISPLAY 0.638298 (-1721 525);
PAINT MONO (-1721 525);
FORCEPROP 2 LAST CDS_LIB mstr_standard
J 0
(-2000 525);
PAINT MONO (-2000 525);
DISPLAY INVISIBLE (-2000 525);
FORCEPROP 1 LAST OFFPAGE TRUE
J 0
(-1675 400);
DISPLAY 1.170213 (-1675 400);
PAINT GREEN (-1675 400);
DISPLAY INVISIBLE (-1675 400);
FORCEPROP 1 LAST COMMENT_BODY TRUE
J 0
(-2045 430);
DISPLAY 1.170213 (-2045 430);
PAINT GREEN (-2045 430);
DISPLAY INVISIBLE (-2045 430);
FORCEPROP 2 LAST PATH I147
J 0
(-1825 600);
DISPLAY 1.021277 (-1825 600);
PAINT ORANGE (-1825 600);
DISPLAY INVISIBLE (-1825 600);
FORCEADD OFFPAGE..4
(-2000 575);
FORCEPROP 2 LAST $XR0 77 
J 0
(-1814 575);
DISPLAY 0.638298 (-1814 575);
PAINT MONO (-1814 575);
FORCEPROP 2 LAST $XR1 78 
J 0
(-1724 575);
DISPLAY 0.638298 (-1724 575);
PAINT MONO (-1724 575);
FORCEPROP 2 LAST CDS_LIB mstr_standard
J 0
(-2000 575);
PAINT MONO (-2000 575);
DISPLAY INVISIBLE (-2000 575);
FORCEPROP 1 LAST OFFPAGE TRUE
J 0
(-1675 450);
DISPLAY 1.170213 (-1675 450);
PAINT GREEN (-1675 450);
DISPLAY INVISIBLE (-1675 450);
FORCEPROP 1 LAST COMMENT_BODY TRUE
J 0
(-2025 475);
DISPLAY 1.170213 (-2025 475);
PAINT GREEN (-2025 475);
DISPLAY INVISIBLE (-2025 475);
FORCEPROP 2 LAST PATH I148
J 0
(-1825 650);
DISPLAY 1.021277 (-1825 650);
PAINT ORANGE (-1825 650);
DISPLAY INVISIBLE (-1825 650);
FORCEADD OFFPAGE..2
(-2000 625);
FORCEPROP 2 LAST $XR0 77 
J 0
(-1811 625);
DISPLAY 0.638298 (-1811 625);
PAINT MONO (-1811 625);
FORCEPROP 2 LAST $XR1 78 
J 0
(-1721 625);
DISPLAY 0.638298 (-1721 625);
PAINT MONO (-1721 625);
FORCEPROP 2 LAST CDS_LIB mstr_standard
J 0
(-2000 625);
PAINT MONO (-2000 625);
DISPLAY INVISIBLE (-2000 625);
FORCEPROP 1 LAST OFFPAGE TRUE
J 0
(-1675 500);
DISPLAY 1.170213 (-1675 500);
PAINT GREEN (-1675 500);
DISPLAY INVISIBLE (-1675 500);
FORCEPROP 1 LAST COMMENT_BODY TRUE
J 0
(-2045 530);
DISPLAY 1.170213 (-2045 530);
PAINT GREEN (-2045 530);
DISPLAY INVISIBLE (-2045 530);
FORCEPROP 2 LAST PATH I149
J 0
(-1825 700);
DISPLAY 1.021277 (-1825 700);
PAINT ORANGE (-1825 700);
DISPLAY INVISIBLE (-1825 700);
FORCEADD TAP..6
(-5575 1175);
FORCEPROP 3 LASTPIN (-5525 1175) SIG_NAME M_G_ECC<2>
J 0
(-5515 1185);
DISPLAY 0.659574 (-5515 1185);
PAINT MONO (-5515 1185);
DISPLAY INVISIBLE (-5515 1185);
FORCEPROP 1 LASTPIN (-5525 1175) BN 2
J 0
(-5577 1183);
DISPLAY 0.617021 (-5577 1183);
PAINT GREEN (-5577 1183);
FORCEPROP 2 LAST CDS_LIB mstr_standard
J 0
(-5575 1175);
PAINT MONO (-5575 1175);
DISPLAY INVISIBLE (-5575 1175);
FORCEPROP 1 LAST BODY_TYPE PLUMBING
J 0
(-5575 1125);
DISPLAY 1.595745 (-5575 1125);
PAINT GREEN (-5575 1125);
DISPLAY INVISIBLE (-5575 1125);
FORCEPROP 1 LAST HDL_TAP TRUE
J 0
(-5250 1050);
DISPLAY 1.595745 (-5250 1050);
PAINT GREEN (-5250 1050);
DISPLAY INVISIBLE (-5250 1050);
FORCEPROP 1 LAST PATH I15
J 0
(-5577 1175);
DISPLAY 0.872340 (-5577 1175);
PAINT GREEN (-5577 1175);
DISPLAY INVISIBLE (-5577 1175);
FORCEADD OFFPAGE..2
(-2000 825);
FORCEPROP 2 LAST $XR0 77 
J 0
(-1811 825);
DISPLAY 0.638298 (-1811 825);
PAINT MONO (-1811 825);
FORCEPROP 2 LAST $XR1 78 
J 0
(-1721 825);
DISPLAY 0.638298 (-1721 825);
PAINT MONO (-1721 825);
FORCEPROP 2 LAST CDS_LIB mstr_standard
J 0
(-2000 825);
PAINT MONO (-2000 825);
DISPLAY INVISIBLE (-2000 825);
FORCEPROP 1 LAST OFFPAGE TRUE
J 0
(-1675 700);
DISPLAY 1.170213 (-1675 700);
PAINT GREEN (-1675 700);
DISPLAY INVISIBLE (-1675 700);
FORCEPROP 1 LAST COMMENT_BODY TRUE
J 0
(-2045 730);
DISPLAY 1.170213 (-2045 730);
PAINT GREEN (-2045 730);
DISPLAY INVISIBLE (-2045 730);
FORCEPROP 2 LAST PATH I150
J 0
(-1825 900);
DISPLAY 1.021277 (-1825 900);
PAINT ORANGE (-1825 900);
DISPLAY INVISIBLE (-1825 900);
FORCEADD OFFPAGE..2
(-2000 925);
FORCEPROP 2 LAST $XR0 77 
J 0
(-1811 925);
DISPLAY 0.638298 (-1811 925);
PAINT MONO (-1811 925);
FORCEPROP 2 LAST $XR1 78 
J 0
(-1721 925);
DISPLAY 0.638298 (-1721 925);
PAINT MONO (-1721 925);
FORCEPROP 2 LAST CDS_LIB mstr_standard
J 0
(-2000 925);
PAINT MONO (-2000 925);
DISPLAY INVISIBLE (-2000 925);
FORCEPROP 1 LAST OFFPAGE TRUE
J 0
(-1675 800);
DISPLAY 1.170213 (-1675 800);
PAINT GREEN (-1675 800);
DISPLAY INVISIBLE (-1675 800);
FORCEPROP 1 LAST COMMENT_BODY TRUE
J 0
(-2045 830);
DISPLAY 1.170213 (-2045 830);
PAINT GREEN (-2045 830);
DISPLAY INVISIBLE (-2045 830);
FORCEPROP 2 LAST PATH I151
J 0
(-1825 1000);
DISPLAY 1.021277 (-1825 1000);
PAINT ORANGE (-1825 1000);
DISPLAY INVISIBLE (-1825 1000);
FORCEADD OFFPAGE..2
(-2000 1375);
FORCEPROP 2 LAST $XR0 77 
J 0
(-1811 1375);
DISPLAY 0.638298 (-1811 1375);
PAINT MONO (-1811 1375);
FORCEPROP 2 LAST $XR1 78 
J 0
(-1721 1375);
DISPLAY 0.638298 (-1721 1375);
PAINT MONO (-1721 1375);
FORCEPROP 2 LAST CDS_LIB mstr_standard
J 0
(-2000 1375);
PAINT MONO (-2000 1375);
DISPLAY INVISIBLE (-2000 1375);
FORCEPROP 1 LAST OFFPAGE TRUE
J 0
(-1675 1250);
DISPLAY 1.170213 (-1675 1250);
PAINT GREEN (-1675 1250);
DISPLAY INVISIBLE (-1675 1250);
FORCEPROP 1 LAST COMMENT_BODY TRUE
J 0
(-2045 1280);
DISPLAY 1.170213 (-2045 1280);
PAINT GREEN (-2045 1280);
DISPLAY INVISIBLE (-2045 1280);
FORCEPROP 2 LAST PATH I152
J 0
(-1825 1450);
DISPLAY 1.021277 (-1825 1450);
PAINT ORANGE (-1825 1450);
DISPLAY INVISIBLE (-1825 1450);
FORCEADD OFFPAGE..2
(-2000 1625);
FORCEPROP 2 LAST $XR0 77 
J 0
(-1811 1625);
DISPLAY 0.638298 (-1811 1625);
PAINT MONO (-1811 1625);
FORCEPROP 2 LAST $XR1 78 
J 0
(-1721 1625);
DISPLAY 0.638298 (-1721 1625);
PAINT MONO (-1721 1625);
FORCEPROP 2 LAST CDS_LIB mstr_standard
J 0
(-2000 1625);
PAINT MONO (-2000 1625);
DISPLAY INVISIBLE (-2000 1625);
FORCEPROP 1 LAST OFFPAGE TRUE
J 0
(-1675 1500);
DISPLAY 1.170213 (-1675 1500);
PAINT GREEN (-1675 1500);
DISPLAY INVISIBLE (-1675 1500);
FORCEPROP 1 LAST COMMENT_BODY TRUE
J 0
(-2045 1530);
DISPLAY 1.170213 (-2045 1530);
PAINT GREEN (-2045 1530);
DISPLAY INVISIBLE (-2045 1530);
FORCEPROP 2 LAST PATH I153
J 0
(-1825 1700);
DISPLAY 1.021277 (-1825 1700);
PAINT ORANGE (-1825 1700);
DISPLAY INVISIBLE (-1825 1700);
FORCEADD OFFPAGE..2
(-2000 1875);
FORCEPROP 2 LAST $XR0 77 
J 0
(-1811 1875);
DISPLAY 0.638298 (-1811 1875);
PAINT MONO (-1811 1875);
FORCEPROP 2 LAST $XR1 78 
J 0
(-1721 1875);
DISPLAY 0.638298 (-1721 1875);
PAINT MONO (-1721 1875);
FORCEPROP 2 LAST CDS_LIB mstr_standard
J 0
(-2000 1875);
PAINT MONO (-2000 1875);
DISPLAY INVISIBLE (-2000 1875);
FORCEPROP 1 LAST OFFPAGE TRUE
J 0
(-1675 1750);
DISPLAY 1.170213 (-1675 1750);
PAINT GREEN (-1675 1750);
DISPLAY INVISIBLE (-1675 1750);
FORCEPROP 1 LAST COMMENT_BODY TRUE
J 0
(-2045 1780);
DISPLAY 1.170213 (-2045 1780);
PAINT GREEN (-2045 1780);
DISPLAY INVISIBLE (-2045 1780);
FORCEPROP 2 LAST PATH I154
J 0
(-1825 1950);
DISPLAY 1.021277 (-1825 1950);
PAINT ORANGE (-1825 1950);
DISPLAY INVISIBLE (-1825 1950);
FORCEADD OFFPAGE..2
(-2000 2825);
FORCEPROP 2 LAST $XR0 77 
J 0
(-1811 2825);
DISPLAY 0.638298 (-1811 2825);
PAINT MONO (-1811 2825);
FORCEPROP 2 LAST $XR1 78 
J 0
(-1721 2825);
DISPLAY 0.638298 (-1721 2825);
PAINT MONO (-1721 2825);
FORCEPROP 2 LAST CDS_LIB mstr_standard
J 0
(-2000 2825);
PAINT MONO (-2000 2825);
DISPLAY INVISIBLE (-2000 2825);
FORCEPROP 1 LAST OFFPAGE TRUE
J 0
(-1675 2700);
DISPLAY 1.170213 (-1675 2700);
PAINT GREEN (-1675 2700);
DISPLAY INVISIBLE (-1675 2700);
FORCEPROP 1 LAST COMMENT_BODY TRUE
J 0
(-2045 2730);
DISPLAY 1.170213 (-2045 2730);
PAINT GREEN (-2045 2730);
DISPLAY INVISIBLE (-2045 2730);
FORCEPROP 2 LAST PATH I155
J 0
(-1825 2900);
DISPLAY 1.021277 (-1825 2900);
PAINT ORANGE (-1825 2900);
DISPLAY INVISIBLE (-1825 2900);
FORCEADD OFFPAGE..3
(-2000 3775);
FORCEPROP 2 LAST $XR0 77 
J 0
(-1786 3775);
DISPLAY 0.638298 (-1786 3775);
PAINT MONO (-1786 3775);
FORCEPROP 2 LAST $XR1 78 
J 0
(-1696 3775);
DISPLAY 0.638298 (-1696 3775);
PAINT MONO (-1696 3775);
FORCEPROP 2 LAST CDS_LIB mstr_standard
J 0
(-2000 3775);
PAINT MONO (-2000 3775);
DISPLAY INVISIBLE (-2000 3775);
FORCEPROP 1 LAST OFFPAGE TRUE
J 0
(-1675 3650);
DISPLAY 1.170213 (-1675 3650);
PAINT GREEN (-1675 3650);
DISPLAY INVISIBLE (-1675 3650);
FORCEPROP 1 LAST COMMENT_BODY TRUE
J 0
(-2050 3675);
DISPLAY 1.170213 (-2050 3675);
PAINT GREEN (-2050 3675);
DISPLAY INVISIBLE (-2050 3675);
FORCEPROP 2 LAST PATH I156
J 0
(-1800 3850);
DISPLAY 1.021277 (-1800 3850);
PAINT ORANGE (-1800 3850);
DISPLAY INVISIBLE (-1800 3850);
FORCEADD TAP..6
R 2
(-2850 4025);
FORCEPROP 3 LASTPIN (-2900 4025) SIG_NAME M_G_DQS_DP<4>
J 0
(-2890 4035);
DISPLAY 0.659574 (-2890 4035);
PAINT MONO (-2890 4035);
DISPLAY INVISIBLE (-2890 4035);
FORCEPROP 1 LASTPIN (-2900 4025) BN 4
J 2
(-2848 4033);
DISPLAY 0.617021 (-2848 4033);
PAINT GREEN (-2848 4033);
FORCEPROP 2 LAST CDS_LIB mstr_standard
J 0
(-2850 4025);
PAINT MONO (-2850 4025);
DISPLAY INVISIBLE (-2850 4025);
FORCEPROP 1 LAST BODY_TYPE PLUMBING
J 2
(-2850 3975);
DISPLAY 1.595745 (-2850 3975);
PAINT GREEN (-2850 3975);
DISPLAY INVISIBLE (-2850 3975);
FORCEPROP 1 LAST HDL_TAP TRUE
J 2
(-3175 3900);
DISPLAY 1.595745 (-3175 3900);
PAINT GREEN (-3175 3900);
DISPLAY INVISIBLE (-3175 3900);
FORCEPROP 1 LAST PATH I157
J 2
(-2848 4025);
DISPLAY 0.872340 (-2848 4025);
PAINT GREEN (-2848 4025);
DISPLAY INVISIBLE (-2848 4025);
FORCEADD TAP..6
R 2
(-2850 4125);
FORCEPROP 3 LASTPIN (-2900 4125) SIG_NAME M_G_DQS_DP<6>
J 0
(-2890 4135);
DISPLAY 0.659574 (-2890 4135);
PAINT MONO (-2890 4135);
DISPLAY INVISIBLE (-2890 4135);
FORCEPROP 1 LASTPIN (-2900 4125) BN 6
J 2
(-2848 4133);
DISPLAY 0.617021 (-2848 4133);
PAINT GREEN (-2848 4133);
FORCEPROP 2 LAST CDS_LIB mstr_standard
J 0
(-2850 4125);
PAINT MONO (-2850 4125);
DISPLAY INVISIBLE (-2850 4125);
FORCEPROP 1 LAST BODY_TYPE PLUMBING
J 2
(-2850 4075);
DISPLAY 1.595745 (-2850 4075);
PAINT GREEN (-2850 4075);
DISPLAY INVISIBLE (-2850 4075);
FORCEPROP 1 LAST HDL_TAP TRUE
J 2
(-3175 4000);
DISPLAY 1.595745 (-3175 4000);
PAINT GREEN (-3175 4000);
DISPLAY INVISIBLE (-3175 4000);
FORCEPROP 1 LAST PATH I158
J 2
(-2848 4125);
DISPLAY 0.872340 (-2848 4125);
PAINT GREEN (-2848 4125);
DISPLAY INVISIBLE (-2848 4125);
FORCEADD TAP..6
R 2
(-2850 4075);
FORCEPROP 3 LASTPIN (-2900 4075) SIG_NAME M_G_DQS_DP<5>
J 0
(-2890 4085);
DISPLAY 0.659574 (-2890 4085);
PAINT MONO (-2890 4085);
DISPLAY INVISIBLE (-2890 4085);
FORCEPROP 1 LASTPIN (-2900 4075) BN 5
J 2
(-2848 4083);
DISPLAY 0.617021 (-2848 4083);
PAINT GREEN (-2848 4083);
FORCEPROP 2 LAST CDS_LIB mstr_standard
J 0
(-2850 4075);
PAINT MONO (-2850 4075);
DISPLAY INVISIBLE (-2850 4075);
FORCEPROP 1 LAST BODY_TYPE PLUMBING
J 2
(-2850 4025);
DISPLAY 1.595745 (-2850 4025);
PAINT GREEN (-2850 4025);
DISPLAY INVISIBLE (-2850 4025);
FORCEPROP 1 LAST HDL_TAP TRUE
J 2
(-3175 3950);
DISPLAY 1.595745 (-3175 3950);
PAINT GREEN (-3175 3950);
DISPLAY INVISIBLE (-3175 3950);
FORCEPROP 1 LAST PATH I159
J 2
(-2848 4075);
DISPLAY 0.872340 (-2848 4075);
PAINT GREEN (-2848 4075);
DISPLAY INVISIBLE (-2848 4075);
FORCEADD TAP..6
(-5575 1275);
FORCEPROP 3 LASTPIN (-5525 1275) SIG_NAME M_G_ECC<4>
J 0
(-5515 1285);
DISPLAY 0.659574 (-5515 1285);
PAINT MONO (-5515 1285);
DISPLAY INVISIBLE (-5515 1285);
FORCEPROP 1 LASTPIN (-5525 1275) BN 4
J 0
(-5577 1283);
DISPLAY 0.617021 (-5577 1283);
PAINT GREEN (-5577 1283);
FORCEPROP 2 LAST CDS_LIB mstr_standard
J 0
(-5575 1275);
PAINT MONO (-5575 1275);
DISPLAY INVISIBLE (-5575 1275);
FORCEPROP 1 LAST BODY_TYPE PLUMBING
J 0
(-5575 1225);
DISPLAY 1.595745 (-5575 1225);
PAINT GREEN (-5575 1225);
DISPLAY INVISIBLE (-5575 1225);
FORCEPROP 1 LAST HDL_TAP TRUE
J 0
(-5250 1150);
DISPLAY 1.595745 (-5250 1150);
PAINT GREEN (-5250 1150);
DISPLAY INVISIBLE (-5250 1150);
FORCEPROP 1 LAST PATH I16
J 0
(-5577 1275);
DISPLAY 0.872340 (-5577 1275);
PAINT GREEN (-5577 1275);
DISPLAY INVISIBLE (-5577 1275);
FORCEADD TAP..6
R 2
(-2850 4175);
FORCEPROP 3 LASTPIN (-2900 4175) SIG_NAME M_G_DQS_DP<7>
J 0
(-2890 4185);
DISPLAY 0.659574 (-2890 4185);
PAINT MONO (-2890 4185);
DISPLAY INVISIBLE (-2890 4185);
FORCEPROP 1 LASTPIN (-2900 4175) BN 7
J 2
(-2848 4183);
DISPLAY 0.617021 (-2848 4183);
PAINT GREEN (-2848 4183);
FORCEPROP 2 LAST CDS_LIB mstr_standard
J 0
(-2850 4175);
PAINT MONO (-2850 4175);
DISPLAY INVISIBLE (-2850 4175);
FORCEPROP 1 LAST BODY_TYPE PLUMBING
J 2
(-2850 4125);
DISPLAY 1.595745 (-2850 4125);
PAINT GREEN (-2850 4125);
DISPLAY INVISIBLE (-2850 4125);
FORCEPROP 1 LAST HDL_TAP TRUE
J 2
(-3175 4050);
DISPLAY 1.595745 (-3175 4050);
PAINT GREEN (-3175 4050);
DISPLAY INVISIBLE (-3175 4050);
FORCEPROP 1 LAST PATH I160
J 2
(-2848 4175);
DISPLAY 0.872340 (-2848 4175);
PAINT GREEN (-2848 4175);
DISPLAY INVISIBLE (-2848 4175);
FORCEADD TAP..6
R 2
(-2850 4225);
FORCEPROP 3 LASTPIN (-2900 4225) SIG_NAME M_G_DQS_DP<8>
J 0
(-2890 4235);
DISPLAY 0.659574 (-2890 4235);
PAINT MONO (-2890 4235);
DISPLAY INVISIBLE (-2890 4235);
FORCEPROP 1 LASTPIN (-2900 4225) BN 8
J 2
(-2848 4233);
DISPLAY 0.617021 (-2848 4233);
PAINT GREEN (-2848 4233);
FORCEPROP 2 LAST CDS_LIB mstr_standard
J 0
(-2850 4225);
PAINT MONO (-2850 4225);
DISPLAY INVISIBLE (-2850 4225);
FORCEPROP 1 LAST BODY_TYPE PLUMBING
J 2
(-2850 4175);
DISPLAY 1.595745 (-2850 4175);
PAINT GREEN (-2850 4175);
DISPLAY INVISIBLE (-2850 4175);
FORCEPROP 1 LAST HDL_TAP TRUE
J 2
(-3175 4100);
DISPLAY 1.595745 (-3175 4100);
PAINT GREEN (-3175 4100);
DISPLAY INVISIBLE (-3175 4100);
FORCEPROP 1 LAST PATH I161
J 2
(-2848 4225);
DISPLAY 0.872340 (-2848 4225);
PAINT GREEN (-2848 4225);
DISPLAY INVISIBLE (-2848 4225);
FORCEADD TAP..6
R 2
(-2850 4275);
FORCEPROP 3 LASTPIN (-2900 4275) SIG_NAME M_G_DQS_DP<9>
J 0
(-2890 4285);
DISPLAY 0.659574 (-2890 4285);
PAINT MONO (-2890 4285);
DISPLAY INVISIBLE (-2890 4285);
FORCEPROP 1 LASTPIN (-2900 4275) BN 9
J 2
(-2848 4283);
DISPLAY 0.617021 (-2848 4283);
PAINT GREEN (-2848 4283);
FORCEPROP 2 LAST CDS_LIB mstr_standard
J 0
(-2850 4275);
PAINT MONO (-2850 4275);
DISPLAY INVISIBLE (-2850 4275);
FORCEPROP 1 LAST BODY_TYPE PLUMBING
J 2
(-2850 4225);
DISPLAY 1.595745 (-2850 4225);
PAINT GREEN (-2850 4225);
DISPLAY INVISIBLE (-2850 4225);
FORCEPROP 1 LAST HDL_TAP TRUE
J 2
(-3175 4150);
DISPLAY 1.595745 (-3175 4150);
PAINT GREEN (-3175 4150);
DISPLAY INVISIBLE (-3175 4150);
FORCEPROP 1 LAST PATH I162
J 2
(-2848 4275);
DISPLAY 0.872340 (-2848 4275);
PAINT GREEN (-2848 4275);
DISPLAY INVISIBLE (-2848 4275);
FORCEADD TAP..6
R 2
(-2850 4325);
FORCEPROP 3 LASTPIN (-2900 4325) SIG_NAME M_G_DQS_DP<10>
J 0
(-2890 4335);
DISPLAY 0.659574 (-2890 4335);
PAINT MONO (-2890 4335);
DISPLAY INVISIBLE (-2890 4335);
FORCEPROP 1 LASTPIN (-2900 4325) BN 10
J 2
(-2848 4333);
DISPLAY 0.617021 (-2848 4333);
PAINT GREEN (-2848 4333);
FORCEPROP 2 LAST CDS_LIB mstr_standard
J 0
(-2850 4325);
PAINT MONO (-2850 4325);
DISPLAY INVISIBLE (-2850 4325);
FORCEPROP 1 LAST BODY_TYPE PLUMBING
J 2
(-2850 4275);
DISPLAY 1.595745 (-2850 4275);
PAINT GREEN (-2850 4275);
DISPLAY INVISIBLE (-2850 4275);
FORCEPROP 1 LAST HDL_TAP TRUE
J 2
(-3175 4200);
DISPLAY 1.595745 (-3175 4200);
PAINT GREEN (-3175 4200);
DISPLAY INVISIBLE (-3175 4200);
FORCEPROP 1 LAST PATH I163
J 2
(-2848 4325);
DISPLAY 0.872340 (-2848 4325);
PAINT GREEN (-2848 4325);
DISPLAY INVISIBLE (-2848 4325);
FORCEADD TAP..6
R 2
(-2850 4375);
FORCEPROP 3 LASTPIN (-2900 4375) SIG_NAME M_G_DQS_DP<11>
J 0
(-2890 4385);
DISPLAY 0.659574 (-2890 4385);
PAINT MONO (-2890 4385);
DISPLAY INVISIBLE (-2890 4385);
FORCEPROP 1 LASTPIN (-2900 4375) BN 11
J 2
(-2848 4383);
DISPLAY 0.617021 (-2848 4383);
PAINT GREEN (-2848 4383);
FORCEPROP 2 LAST CDS_LIB mstr_standard
J 0
(-2850 4375);
PAINT MONO (-2850 4375);
DISPLAY INVISIBLE (-2850 4375);
FORCEPROP 1 LAST BODY_TYPE PLUMBING
J 2
(-2850 4325);
DISPLAY 1.595745 (-2850 4325);
PAINT GREEN (-2850 4325);
DISPLAY INVISIBLE (-2850 4325);
FORCEPROP 1 LAST HDL_TAP TRUE
J 2
(-3175 4250);
DISPLAY 1.595745 (-3175 4250);
PAINT GREEN (-3175 4250);
DISPLAY INVISIBLE (-3175 4250);
FORCEPROP 1 LAST PATH I164
J 2
(-2848 4375);
DISPLAY 0.872340 (-2848 4375);
PAINT GREEN (-2848 4375);
DISPLAY INVISIBLE (-2848 4375);
FORCEADD TAP..6
R 2
(-2850 4525);
FORCEPROP 3 LASTPIN (-2900 4525) SIG_NAME M_G_DQS_DP<14>
J 0
(-2890 4535);
DISPLAY 0.659574 (-2890 4535);
PAINT MONO (-2890 4535);
DISPLAY INVISIBLE (-2890 4535);
FORCEPROP 1 LASTPIN (-2900 4525) BN 14
J 2
(-2848 4533);
DISPLAY 0.617021 (-2848 4533);
PAINT GREEN (-2848 4533);
FORCEPROP 2 LAST CDS_LIB mstr_standard
J 0
(-2850 4525);
PAINT MONO (-2850 4525);
DISPLAY INVISIBLE (-2850 4525);
FORCEPROP 1 LAST BODY_TYPE PLUMBING
J 2
(-2850 4475);
DISPLAY 1.595745 (-2850 4475);
PAINT GREEN (-2850 4475);
DISPLAY INVISIBLE (-2850 4475);
FORCEPROP 1 LAST HDL_TAP TRUE
J 2
(-3175 4400);
DISPLAY 1.595745 (-3175 4400);
PAINT GREEN (-3175 4400);
DISPLAY INVISIBLE (-3175 4400);
FORCEPROP 1 LAST PATH I165
J 2
(-2848 4525);
DISPLAY 0.872340 (-2848 4525);
PAINT GREEN (-2848 4525);
DISPLAY INVISIBLE (-2848 4525);
FORCEADD TAP..6
R 2
(-2850 4475);
FORCEPROP 3 LASTPIN (-2900 4475) SIG_NAME M_G_DQS_DP<13>
J 0
(-2890 4485);
DISPLAY 0.659574 (-2890 4485);
PAINT MONO (-2890 4485);
DISPLAY INVISIBLE (-2890 4485);
FORCEPROP 1 LASTPIN (-2900 4475) BN 13
J 2
(-2848 4483);
DISPLAY 0.617021 (-2848 4483);
PAINT GREEN (-2848 4483);
FORCEPROP 2 LAST CDS_LIB mstr_standard
J 0
(-2850 4475);
PAINT MONO (-2850 4475);
DISPLAY INVISIBLE (-2850 4475);
FORCEPROP 1 LAST BODY_TYPE PLUMBING
J 2
(-2850 4425);
DISPLAY 1.595745 (-2850 4425);
PAINT GREEN (-2850 4425);
DISPLAY INVISIBLE (-2850 4425);
FORCEPROP 1 LAST HDL_TAP TRUE
J 2
(-3175 4350);
DISPLAY 1.595745 (-3175 4350);
PAINT GREEN (-3175 4350);
DISPLAY INVISIBLE (-3175 4350);
FORCEPROP 1 LAST PATH I166
J 2
(-2848 4475);
DISPLAY 0.872340 (-2848 4475);
PAINT GREEN (-2848 4475);
DISPLAY INVISIBLE (-2848 4475);
FORCEADD TAP..6
R 2
(-2850 4425);
FORCEPROP 3 LASTPIN (-2900 4425) SIG_NAME M_G_DQS_DP<12>
J 0
(-2890 4435);
DISPLAY 0.659574 (-2890 4435);
PAINT MONO (-2890 4435);
DISPLAY INVISIBLE (-2890 4435);
FORCEPROP 1 LASTPIN (-2900 4425) BN 12
J 2
(-2848 4433);
DISPLAY 0.617021 (-2848 4433);
PAINT GREEN (-2848 4433);
FORCEPROP 2 LAST CDS_LIB mstr_standard
J 0
(-2850 4425);
PAINT MONO (-2850 4425);
DISPLAY INVISIBLE (-2850 4425);
FORCEPROP 1 LAST BODY_TYPE PLUMBING
J 2
(-2850 4375);
DISPLAY 1.595745 (-2850 4375);
PAINT GREEN (-2850 4375);
DISPLAY INVISIBLE (-2850 4375);
FORCEPROP 1 LAST HDL_TAP TRUE
J 2
(-3175 4300);
DISPLAY 1.595745 (-3175 4300);
PAINT GREEN (-3175 4300);
DISPLAY INVISIBLE (-3175 4300);
FORCEPROP 1 LAST PATH I167
J 2
(-2848 4425);
DISPLAY 0.872340 (-2848 4425);
PAINT GREEN (-2848 4425);
DISPLAY INVISIBLE (-2848 4425);
FORCEADD TAP..6
R 2
(-2850 4575);
FORCEPROP 3 LASTPIN (-2900 4575) SIG_NAME M_G_DQS_DP<15>
J 0
(-2890 4585);
DISPLAY 0.659574 (-2890 4585);
PAINT MONO (-2890 4585);
DISPLAY INVISIBLE (-2890 4585);
FORCEPROP 1 LASTPIN (-2900 4575) BN 15
J 2
(-2848 4583);
DISPLAY 0.617021 (-2848 4583);
PAINT GREEN (-2848 4583);
FORCEPROP 2 LAST CDS_LIB mstr_standard
J 0
(-2850 4575);
PAINT MONO (-2850 4575);
DISPLAY INVISIBLE (-2850 4575);
FORCEPROP 1 LAST BODY_TYPE PLUMBING
J 2
(-2850 4525);
DISPLAY 1.595745 (-2850 4525);
PAINT GREEN (-2850 4525);
DISPLAY INVISIBLE (-2850 4525);
FORCEPROP 1 LAST HDL_TAP TRUE
J 2
(-3175 4450);
DISPLAY 1.595745 (-3175 4450);
PAINT GREEN (-3175 4450);
DISPLAY INVISIBLE (-3175 4450);
FORCEPROP 1 LAST PATH I168
J 2
(-2848 4575);
DISPLAY 0.872340 (-2848 4575);
PAINT GREEN (-2848 4575);
DISPLAY INVISIBLE (-2848 4575);
FORCEADD TAP..6
R 2
(-2850 4625);
FORCEPROP 3 LASTPIN (-2900 4625) SIG_NAME M_G_DQS_DP<16>
J 0
(-2890 4635);
DISPLAY 0.659574 (-2890 4635);
PAINT MONO (-2890 4635);
DISPLAY INVISIBLE (-2890 4635);
FORCEPROP 1 LASTPIN (-2900 4625) BN 16
J 2
(-2848 4633);
DISPLAY 0.617021 (-2848 4633);
PAINT GREEN (-2848 4633);
FORCEPROP 2 LAST CDS_LIB mstr_standard
J 0
(-2850 4625);
PAINT MONO (-2850 4625);
DISPLAY INVISIBLE (-2850 4625);
FORCEPROP 1 LAST BODY_TYPE PLUMBING
J 2
(-2850 4575);
DISPLAY 1.595745 (-2850 4575);
PAINT GREEN (-2850 4575);
DISPLAY INVISIBLE (-2850 4575);
FORCEPROP 1 LAST HDL_TAP TRUE
J 2
(-3175 4500);
DISPLAY 1.595745 (-3175 4500);
PAINT GREEN (-3175 4500);
DISPLAY INVISIBLE (-3175 4500);
FORCEPROP 1 LAST PATH I169
J 2
(-2848 4625);
DISPLAY 0.872340 (-2848 4625);
PAINT GREEN (-2848 4625);
DISPLAY INVISIBLE (-2848 4625);
FORCEADD TAP..6
(-5575 1225);
FORCEPROP 3 LASTPIN (-5525 1225) SIG_NAME M_G_ECC<3>
J 0
(-5515 1235);
DISPLAY 0.659574 (-5515 1235);
PAINT MONO (-5515 1235);
DISPLAY INVISIBLE (-5515 1235);
FORCEPROP 1 LASTPIN (-5525 1225) BN 3
J 0
(-5577 1233);
DISPLAY 0.617021 (-5577 1233);
PAINT GREEN (-5577 1233);
FORCEPROP 2 LAST CDS_LIB mstr_standard
J 0
(-5575 1225);
PAINT MONO (-5575 1225);
DISPLAY INVISIBLE (-5575 1225);
FORCEPROP 1 LAST BODY_TYPE PLUMBING
J 0
(-5575 1175);
DISPLAY 1.595745 (-5575 1175);
PAINT GREEN (-5575 1175);
DISPLAY INVISIBLE (-5575 1175);
FORCEPROP 1 LAST HDL_TAP TRUE
J 0
(-5250 1100);
DISPLAY 1.595745 (-5250 1100);
PAINT GREEN (-5250 1100);
DISPLAY INVISIBLE (-5250 1100);
FORCEPROP 1 LAST PATH I17
J 0
(-5577 1225);
DISPLAY 0.872340 (-5577 1225);
PAINT GREEN (-5577 1225);
DISPLAY INVISIBLE (-5577 1225);
FORCEADD TAP..6
R 2
(-2850 4675);
FORCEPROP 3 LASTPIN (-2900 4675) SIG_NAME M_G_DQS_DP<17>
J 0
(-2890 4685);
DISPLAY 0.659574 (-2890 4685);
PAINT MONO (-2890 4685);
DISPLAY INVISIBLE (-2890 4685);
FORCEPROP 1 LASTPIN (-2900 4675) BN 17
J 2
(-2848 4683);
DISPLAY 0.617021 (-2848 4683);
PAINT GREEN (-2848 4683);
FORCEPROP 2 LAST CDS_LIB mstr_standard
J 2
(-2850 4675);
PAINT MONO (-2850 4675);
DISPLAY INVISIBLE (-2850 4675);
FORCEPROP 1 LAST BODY_TYPE PLUMBING
J 2
(-2850 4625);
DISPLAY 1.595745 (-2850 4625);
PAINT GREEN (-2850 4625);
DISPLAY INVISIBLE (-2850 4625);
FORCEPROP 1 LAST HDL_TAP TRUE
J 2
(-3175 4550);
DISPLAY 1.595745 (-3175 4550);
PAINT GREEN (-3175 4550);
DISPLAY INVISIBLE (-3175 4550);
FORCEPROP 1 LAST PATH I170
J 2
(-2848 4675);
DISPLAY 0.872340 (-2848 4675);
PAINT GREEN (-2848 4675);
DISPLAY INVISIBLE (-2848 4675);
FORCEADD OFFPAGE..3
(-2000 4750);
FORCEPROP 2 LAST $XR0 77 
J 0
(-1786 4750);
DISPLAY 0.638298 (-1786 4750);
PAINT MONO (-1786 4750);
FORCEPROP 2 LAST $XR1 78 
J 0
(-1696 4750);
DISPLAY 0.638298 (-1696 4750);
PAINT MONO (-1696 4750);
FORCEPROP 2 LAST CDS_LIB mstr_standard
J 0
(-2000 4750);
PAINT MONO (-2000 4750);
DISPLAY INVISIBLE (-2000 4750);
FORCEPROP 1 LAST OFFPAGE TRUE
J 0
(-1675 4625);
DISPLAY 1.170213 (-1675 4625);
PAINT GREEN (-1675 4625);
DISPLAY INVISIBLE (-1675 4625);
FORCEPROP 1 LAST COMMENT_BODY TRUE
J 0
(-2050 4650);
DISPLAY 1.170213 (-2050 4650);
PAINT GREEN (-2050 4650);
DISPLAY INVISIBLE (-2050 4650);
FORCEPROP 2 LAST PATH I171
J 0
(-1800 4825);
DISPLAY 1.021277 (-1800 4825);
PAINT ORANGE (-1800 4825);
DISPLAY INVISIBLE (-1800 4825);
FORCEADD SKX_EXT_B..3
(-4175 2575);
FORCEPROP 1 LAST LOCATION U2D1
J 0
(-4975 4925);
DISPLAY 0.617021 (-4975 4925);
PAINT AQUA (-4975 4925);
FORCEPROP 1 LAST PART_NUMBER TBD
J 0
(-4975 325);
DISPLAY 0.617021 (-4975 325);
PAINT BLUE (-4975 325);
FORCEPROP 1 LAST MATERIAL IC
J 0
(-4975 4875);
DISPLAY 0.617021 (-4975 4875);
PAINT SKYBLUE (-4975 4875);
FORCEPROP 2 LASTPIN (-3325 525) $PN D53
J 0
(-3315 535);
DISPLAY 0.617021 (-3315 535);
PAINT ORANGE (-3315 535);
FORCEPROP 2 LASTPIN (-3325 1575) $PN G48
J 0
(-3315 1585);
DISPLAY 0.617021 (-3315 1585);
PAINT ORANGE (-3315 1585);
FORCEPROP 2 LASTPIN (-3325 1525) $PN G50
J 0
(-3315 1535);
DISPLAY 0.617021 (-3315 1535);
PAINT ORANGE (-3315 1535);
FORCEPROP 2 LASTPIN (-3325 1475) $PN C48
J 0
(-3315 1485);
DISPLAY 0.617021 (-3315 1485);
PAINT ORANGE (-3315 1485);
FORCEPROP 2 LASTPIN (-3325 1425) $PN C50
J 0
(-3315 1435);
DISPLAY 0.617021 (-3315 1435);
PAINT ORANGE (-3315 1435);
FORCEPROP 2 LASTPIN (-3325 2775) $PN K47
J 0
(-3315 2785);
DISPLAY 0.617021 (-3315 2785);
PAINT ORANGE (-3315 2785);
FORCEPROP 2 LASTPIN (-3325 2725) $PN D51
J 0
(-3315 2735);
DISPLAY 0.617021 (-3315 2735);
PAINT ORANGE (-3315 2735);
FORCEPROP 2 LASTPIN (-3325 2675) $PN K49
J 0
(-3315 2685);
DISPLAY 0.617021 (-3315 2685);
PAINT ORANGE (-3315 2685);
FORCEPROP 2 LASTPIN (-3325 2625) $PN F51
J 0
(-3315 2635);
DISPLAY 0.617021 (-3315 2635);
PAINT ORANGE (-3315 2635);
FORCEPROP 2 LASTPIN (-3325 2575) $PN J48
J 0
(-3315 2585);
DISPLAY 0.617021 (-3315 2585);
PAINT ORANGE (-3315 2585);
FORCEPROP 2 LASTPIN (-3325 2525) $PN J64
J 0
(-3315 2535);
DISPLAY 0.617021 (-3315 2535);
PAINT ORANGE (-3315 2535);
FORCEPROP 2 LASTPIN (-3325 2475) $PN G62
J 0
(-3315 2485);
DISPLAY 0.617021 (-3315 2485);
PAINT ORANGE (-3315 2485);
FORCEPROP 2 LASTPIN (-3325 2425) $PN J54
J 0
(-3315 2435);
DISPLAY 0.617021 (-3315 2435);
PAINT ORANGE (-3315 2435);
FORCEPROP 2 LASTPIN (-3325 2375) $PN F61
J 0
(-3315 2385);
DISPLAY 0.617021 (-3315 2385);
PAINT ORANGE (-3315 2385);
FORCEPROP 2 LASTPIN (-3325 2325) $PN C60
J 0
(-3315 2335);
DISPLAY 0.617021 (-3315 2335);
PAINT ORANGE (-3315 2335);
FORCEPROP 2 LASTPIN (-3325 2275) $PN G60
J 0
(-3315 2285);
DISPLAY 0.617021 (-3315 2285);
PAINT ORANGE (-3315 2285);
FORCEPROP 2 LASTPIN (-3325 2225) $PN D59
J 0
(-3315 2235);
DISPLAY 0.617021 (-3315 2235);
PAINT ORANGE (-3315 2235);
FORCEPROP 2 LASTPIN (-3325 2175) $PN F59
J 0
(-3315 2185);
DISPLAY 0.617021 (-3315 2185);
PAINT ORANGE (-3315 2185);
FORCEPROP 2 LASTPIN (-3325 2125) $PN G58
J 0
(-3315 2135);
DISPLAY 0.617021 (-3315 2135);
PAINT ORANGE (-3315 2135);
FORCEPROP 2 LASTPIN (-3325 2075) $PN C58
J 0
(-3315 2085);
DISPLAY 0.617021 (-3315 2085);
PAINT ORANGE (-3315 2085);
FORCEPROP 2 LASTPIN (-3325 2025) $PN D57
J 0
(-3315 2035);
DISPLAY 0.617021 (-3315 2035);
PAINT ORANGE (-3315 2035);
FORCEPROP 2 LASTPIN (-3325 1975) $PN F57
J 0
(-3315 1985);
DISPLAY 0.617021 (-3315 1985);
PAINT ORANGE (-3315 1985);
FORCEPROP 2 LASTPIN (-3325 1925) $PN F53
J 0
(-3315 1935);
DISPLAY 0.617021 (-3315 1935);
PAINT ORANGE (-3315 1935);
FORCEPROP 2 LASTPIN (-5025 1425) $PN AG66
J 2
(-5035 1435);
DISPLAY 0.617021 (-5035 1435);
PAINT ORANGE (-5035 1435);
FORCEPROP 2 LASTPIN (-5025 1375) $PN AC66
J 2
(-5035 1385);
DISPLAY 0.617021 (-5035 1385);
PAINT ORANGE (-5035 1385);
FORCEPROP 2 LASTPIN (-5025 1325) $PN AF69
J 2
(-5035 1335);
DISPLAY 0.617021 (-5035 1335);
PAINT ORANGE (-5035 1335);
FORCEPROP 2 LASTPIN (-5025 1275) $PN AD69
J 2
(-5035 1285);
DISPLAY 0.617021 (-5035 1285);
PAINT ORANGE (-5035 1285);
FORCEPROP 2 LASTPIN (-5025 1225) $PN AF65
J 2
(-5035 1235);
DISPLAY 0.617021 (-5035 1235);
PAINT ORANGE (-5035 1235);
FORCEPROP 2 LASTPIN (-5025 1175) $PN AD65
J 2
(-5035 1185);
DISPLAY 0.617021 (-5035 1185);
PAINT ORANGE (-5035 1185);
FORCEPROP 2 LASTPIN (-5025 1125) $PN AG68
J 2
(-5035 1135);
DISPLAY 0.617021 (-5035 1135);
PAINT ORANGE (-5035 1135);
FORCEPROP 2 LASTPIN (-5025 1075) $PN AC68
J 2
(-5035 1085);
DISPLAY 0.617021 (-5035 1085);
PAINT ORANGE (-5035 1085);
FORCEPROP 2 LASTPIN (-3325 4675) $PN AD67
J 0
(-3315 4685);
DISPLAY 0.617021 (-3315 4685);
PAINT ORANGE (-3315 4685);
FORCEPROP 2 LASTPIN (-3325 4625) $PN L24
J 0
(-3315 4635);
DISPLAY 0.617021 (-3315 4635);
PAINT ORANGE (-3315 4635);
FORCEPROP 2 LASTPIN (-3325 4575) $PN L30
J 0
(-3315 4585);
DISPLAY 0.617021 (-3315 4585);
PAINT ORANGE (-3315 4585);
FORCEPROP 2 LASTPIN (-3325 4525) $PN L36
J 0
(-3315 4535);
DISPLAY 0.617021 (-3315 4535);
PAINT ORANGE (-3315 4535);
FORCEPROP 2 LASTPIN (-3325 4475) $PN C40
J 0
(-3315 4485);
DISPLAY 0.617021 (-3315 4485);
PAINT ORANGE (-3315 4485);
FORCEPROP 2 LASTPIN (-3325 4425) $PN M75
J 0
(-3315 4435);
DISPLAY 0.617021 (-3315 4435);
PAINT ORANGE (-3315 4435);
FORCEPROP 2 LASTPIN (-3325 4375) $PN T81
J 0
(-3315 4385);
DISPLAY 0.617021 (-3315 4385);
PAINT ORANGE (-3315 4385);
FORCEPROP 2 LASTPIN (-3325 4325) $PN V85
J 0
(-3315 4335);
DISPLAY 0.617021 (-3315 4335);
PAINT ORANGE (-3315 4335);
FORCEPROP 2 LASTPIN (-3325 4275) $PN AM85
J 0
(-3315 4285);
DISPLAY 0.617021 (-3315 4285);
PAINT ORANGE (-3315 4285);
FORCEPROP 2 LASTPIN (-3325 4225) $PN AF67
J 0
(-3315 4235);
DISPLAY 0.617021 (-3315 4235);
PAINT ORANGE (-3315 4235);
FORCEPROP 2 LASTPIN (-3325 4175) $PN R24
J 0
(-3315 4185);
DISPLAY 0.617021 (-3315 4185);
PAINT ORANGE (-3315 4185);
FORCEPROP 2 LASTPIN (-3325 4125) $PN N30
J 0
(-3315 4135);
DISPLAY 0.617021 (-3315 4135);
PAINT ORANGE (-3315 4135);
FORCEPROP 2 LASTPIN (-3325 4075) $PN N36
J 0
(-3315 4085);
DISPLAY 0.617021 (-3315 4085);
PAINT ORANGE (-3315 4085);
FORCEPROP 2 LASTPIN (-3325 4025) $PN E40
J 0
(-3315 4035);
DISPLAY 0.617021 (-3315 4035);
PAINT ORANGE (-3315 4035);
FORCEPROP 2 LASTPIN (-3325 3975) $PN P75
J 0
(-3315 3985);
DISPLAY 0.617021 (-3315 3985);
PAINT ORANGE (-3315 3985);
FORCEPROP 2 LASTPIN (-3325 3925) $PN R80
J 0
(-3315 3935);
DISPLAY 0.617021 (-3315 3935);
PAINT ORANGE (-3315 3935);
FORCEPROP 2 LASTPIN (-3325 3875) $PN P85
J 0
(-3315 3885);
DISPLAY 0.617021 (-3315 3885);
PAINT ORANGE (-3315 3885);
FORCEPROP 2 LASTPIN (-3325 3825) $PN AH85
J 0
(-3315 3835);
DISPLAY 0.617021 (-3315 3835);
PAINT ORANGE (-3315 3835);
FORCEPROP 2 LASTPIN (-3325 3725) $PN AB67
J 0
(-3315 3735);
DISPLAY 0.617021 (-3315 3735);
PAINT ORANGE (-3315 3735);
FORCEPROP 2 LASTPIN (-3325 3675) $PN J24
J 0
(-3315 3685);
DISPLAY 0.617021 (-3315 3685);
PAINT ORANGE (-3315 3685);
FORCEPROP 2 LASTPIN (-3325 3625) $PN J30
J 0
(-3315 3635);
DISPLAY 0.617021 (-3315 3635);
PAINT ORANGE (-3315 3635);
FORCEPROP 2 LASTPIN (-3325 3575) $PN J36
J 0
(-3315 3585);
DISPLAY 0.617021 (-3315 3585);
PAINT ORANGE (-3315 3585);
FORCEPROP 2 LASTPIN (-3325 3525) $PN A40
J 0
(-3315 3535);
DISPLAY 0.617021 (-3315 3535);
PAINT ORANGE (-3315 3535);
FORCEPROP 2 LASTPIN (-3325 3475) $PN K75
J 0
(-3315 3485);
DISPLAY 0.617021 (-3315 3485);
PAINT ORANGE (-3315 3485);
FORCEPROP 2 LASTPIN (-3325 3425) $PN U82
J 0
(-3315 3435);
DISPLAY 0.617021 (-3315 3435);
PAINT ORANGE (-3315 3435);
FORCEPROP 2 LASTPIN (-3325 3375) $PN U84
J 0
(-3315 3385);
DISPLAY 0.617021 (-3315 3385);
PAINT ORANGE (-3315 3385);
FORCEPROP 2 LASTPIN (-3325 3325) $PN AL84
J 0
(-3315 3335);
DISPLAY 0.617021 (-3315 3335);
PAINT ORANGE (-3315 3335);
FORCEPROP 2 LASTPIN (-3325 3275) $PN AH67
J 0
(-3315 3285);
DISPLAY 0.617021 (-3315 3285);
PAINT ORANGE (-3315 3285);
FORCEPROP 2 LASTPIN (-3325 3225) $PN N24
J 0
(-3315 3235);
DISPLAY 0.617021 (-3315 3235);
PAINT ORANGE (-3315 3235);
FORCEPROP 2 LASTPIN (-3325 3175) $PN R30
J 0
(-3315 3185);
DISPLAY 0.617021 (-3315 3185);
PAINT ORANGE (-3315 3185);
FORCEPROP 2 LASTPIN (-3325 3125) $PN R36
J 0
(-3315 3135);
DISPLAY 0.617021 (-3315 3135);
PAINT ORANGE (-3315 3135);
FORCEPROP 2 LASTPIN (-3325 3075) $PN G40
J 0
(-3315 3085);
DISPLAY 0.617021 (-3315 3085);
PAINT ORANGE (-3315 3085);
FORCEPROP 2 LASTPIN (-3325 3025) $PN T75
J 0
(-3315 3035);
DISPLAY 0.617021 (-3315 3035);
PAINT ORANGE (-3315 3035);
FORCEPROP 2 LASTPIN (-3325 2975) $PN P79
J 0
(-3315 2985);
DISPLAY 0.617021 (-3315 2985);
PAINT ORANGE (-3315 2985);
FORCEPROP 2 LASTPIN (-3325 2925) $PN R84
J 0
(-3315 2935);
DISPLAY 0.617021 (-3315 2935);
PAINT ORANGE (-3315 2935);
FORCEPROP 2 LASTPIN (-3325 2875) $PN AJ84
J 0
(-3315 2885);
DISPLAY 0.617021 (-3315 2885);
PAINT ORANGE (-3315 2885);
FORCEPROP 2 LASTPIN (-5025 4675) $PN K23
J 2
(-5035 4685);
DISPLAY 0.617021 (-5035 4685);
PAINT ORANGE (-5035 4685);
FORCEPROP 2 LASTPIN (-5025 4625) $PN H23
J 2
(-5035 4635);
DISPLAY 0.617021 (-5035 4635);
PAINT ORANGE (-5035 4635);
FORCEPROP 2 LASTPIN (-5025 4575) $PN N26
J 2
(-5035 4585);
DISPLAY 0.617021 (-5035 4585);
PAINT ORANGE (-5035 4585);
FORCEPROP 2 LASTPIN (-5025 4525) $PN L26
J 2
(-5035 4535);
DISPLAY 0.617021 (-5035 4535);
PAINT ORANGE (-5035 4535);
FORCEPROP 2 LASTPIN (-5025 4475) $PN T23
J 2
(-5035 4485);
DISPLAY 0.617021 (-5035 4485);
PAINT ORANGE (-5035 4485);
FORCEPROP 2 LASTPIN (-5025 4425) $PN P23
J 2
(-5035 4435);
DISPLAY 0.617021 (-5035 4435);
PAINT ORANGE (-5035 4435);
FORCEPROP 2 LASTPIN (-5025 4375) $PN P25
J 2
(-5035 4385);
DISPLAY 0.617021 (-5035 4385);
PAINT ORANGE (-5035 4385);
FORCEPROP 2 LASTPIN (-5025 4325) $PN K25
J 2
(-5035 4335);
DISPLAY 0.617021 (-5035 4335);
PAINT ORANGE (-5035 4335);
FORCEPROP 2 LASTPIN (-5025 4275) $PN P29
J 2
(-5035 4285);
DISPLAY 0.617021 (-5035 4285);
PAINT ORANGE (-5035 4285);
FORCEPROP 2 LASTPIN (-5025 4225) $PN K29
J 2
(-5035 4235);
DISPLAY 0.617021 (-5035 4235);
PAINT ORANGE (-5035 4235);
FORCEPROP 2 LASTPIN (-5025 4175) $PN N32
J 2
(-5035 4185);
DISPLAY 0.617021 (-5035 4185);
PAINT ORANGE (-5035 4185);
FORCEPROP 2 LASTPIN (-5025 4125) $PN L32
J 2
(-5035 4135);
DISPLAY 0.617021 (-5035 4135);
PAINT ORANGE (-5035 4135);
FORCEPROP 2 LASTPIN (-5025 4075) $PN N28
J 2
(-5035 4085);
DISPLAY 0.617021 (-5035 4085);
PAINT ORANGE (-5035 4085);
FORCEPROP 2 LASTPIN (-5025 4025) $PN L28
J 2
(-5035 4035);
DISPLAY 0.617021 (-5035 4035);
PAINT ORANGE (-5035 4035);
FORCEPROP 2 LASTPIN (-5025 3975) $PN P31
J 2
(-5035 3985);
DISPLAY 0.617021 (-5035 3985);
PAINT ORANGE (-5035 3985);
FORCEPROP 2 LASTPIN (-5025 3925) $PN K31
J 2
(-5035 3935);
DISPLAY 0.617021 (-5035 3935);
PAINT ORANGE (-5035 3935);
FORCEPROP 2 LASTPIN (-5025 3875) $PN P35
J 2
(-5035 3885);
DISPLAY 0.617021 (-5035 3885);
PAINT ORANGE (-5035 3885);
FORCEPROP 2 LASTPIN (-5025 3825) $PN K35
J 2
(-5035 3835);
DISPLAY 0.617021 (-5035 3835);
PAINT ORANGE (-5035 3835);
FORCEPROP 2 LASTPIN (-5025 3775) $PN N38
J 2
(-5035 3785);
DISPLAY 0.617021 (-5035 3785);
PAINT ORANGE (-5035 3785);
FORCEPROP 2 LASTPIN (-5025 3725) $PN L38
J 2
(-5035 3735);
DISPLAY 0.617021 (-5035 3735);
PAINT ORANGE (-5035 3735);
FORCEPROP 2 LASTPIN (-5025 3675) $PN N34
J 2
(-5035 3685);
DISPLAY 0.617021 (-5035 3685);
PAINT ORANGE (-5035 3685);
FORCEPROP 2 LASTPIN (-5025 3625) $PN L34
J 2
(-5035 3635);
DISPLAY 0.617021 (-5035 3635);
PAINT ORANGE (-5035 3635);
FORCEPROP 2 LASTPIN (-5025 3575) $PN P37
J 2
(-5035 3585);
DISPLAY 0.617021 (-5035 3585);
PAINT ORANGE (-5035 3585);
FORCEPROP 2 LASTPIN (-5025 3525) $PN K37
J 2
(-5035 3535);
DISPLAY 0.617021 (-5035 3535);
PAINT ORANGE (-5035 3535);
FORCEPROP 2 LASTPIN (-5025 3475) $PN F39
J 2
(-5035 3485);
DISPLAY 0.617021 (-5035 3485);
PAINT ORANGE (-5035 3485);
FORCEPROP 2 LASTPIN (-5025 3425) $PN B39
J 2
(-5035 3435);
DISPLAY 0.617021 (-5035 3435);
PAINT ORANGE (-5035 3435);
FORCEPROP 2 LASTPIN (-5025 3375) $PN F41
J 2
(-5035 3385);
DISPLAY 0.617021 (-5035 3385);
PAINT ORANGE (-5035 3385);
FORCEPROP 2 LASTPIN (-5025 3325) $PN E42
J 2
(-5035 3335);
DISPLAY 0.617021 (-5035 3335);
PAINT ORANGE (-5035 3335);
FORCEPROP 2 LASTPIN (-5025 3275) $PN E38
J 2
(-5035 3285);
DISPLAY 0.617021 (-5035 3285);
PAINT ORANGE (-5035 3285);
FORCEPROP 2 LASTPIN (-5025 3225) $PN C38
J 2
(-5035 3235);
DISPLAY 0.617021 (-5035 3235);
PAINT ORANGE (-5035 3235);
FORCEPROP 2 LASTPIN (-5025 3175) $PN B41
J 2
(-5035 3185);
DISPLAY 0.617021 (-5035 3185);
PAINT ORANGE (-5035 3185);
FORCEPROP 2 LASTPIN (-5025 3125) $PN C42
J 2
(-5035 3135);
DISPLAY 0.617021 (-5035 3135);
PAINT ORANGE (-5035 3135);
FORCEPROP 2 LASTPIN (-5025 3075) $PN R74
J 2
(-5035 3085);
DISPLAY 0.617021 (-5035 3085);
PAINT ORANGE (-5035 3085);
FORCEPROP 2 LASTPIN (-5025 3025) $PN L74
J 2
(-5035 3035);
DISPLAY 0.617021 (-5035 3035);
PAINT ORANGE (-5035 3035);
FORCEPROP 2 LASTPIN (-5025 2975) $PN P77
J 2
(-5035 2985);
DISPLAY 0.617021 (-5035 2985);
PAINT ORANGE (-5035 2985);
FORCEPROP 2 LASTPIN (-5025 2925) $PN M77
J 2
(-5035 2935);
DISPLAY 0.617021 (-5035 2935);
PAINT ORANGE (-5035 2935);
FORCEPROP 2 LASTPIN (-5025 2875) $PN P73
J 2
(-5035 2885);
DISPLAY 0.617021 (-5035 2885);
PAINT ORANGE (-5035 2885);
FORCEPROP 2 LASTPIN (-5025 2825) $PN M73
J 2
(-5035 2835);
DISPLAY 0.617021 (-5035 2835);
PAINT ORANGE (-5035 2835);
FORCEPROP 2 LASTPIN (-5025 2775) $PN R76
J 2
(-5035 2785);
DISPLAY 0.617021 (-5035 2785);
PAINT ORANGE (-5035 2785);
FORCEPROP 2 LASTPIN (-5025 2725) $PN L76
J 2
(-5035 2735);
DISPLAY 0.617021 (-5035 2735);
PAINT ORANGE (-5035 2735);
FORCEPROP 2 LASTPIN (-5025 2675) $PN N80
J 2
(-5035 2685);
DISPLAY 0.617021 (-5035 2685);
PAINT ORANGE (-5035 2685);
FORCEPROP 2 LASTPIN (-5025 2625) $PN R82
J 2
(-5035 2635);
DISPLAY 0.617021 (-5035 2635);
PAINT ORANGE (-5035 2635);
FORCEPROP 2 LASTPIN (-5025 2575) $PN V79
J 2
(-5035 2585);
DISPLAY 0.617021 (-5035 2585);
PAINT ORANGE (-5035 2585);
FORCEPROP 2 LASTPIN (-5025 2525) $PN W80
J 2
(-5035 2535);
DISPLAY 0.617021 (-5035 2535);
PAINT ORANGE (-5035 2535);
FORCEPROP 2 LASTPIN (-5025 2475) $PN M81
J 2
(-5035 2485);
DISPLAY 0.617021 (-5035 2485);
PAINT ORANGE (-5035 2485);
FORCEPROP 2 LASTPIN (-5025 2425) $PN N82
J 2
(-5035 2435);
DISPLAY 0.617021 (-5035 2435);
PAINT ORANGE (-5035 2435);
FORCEPROP 2 LASTPIN (-5025 2375) $PN T79
J 2
(-5035 2385);
DISPLAY 0.617021 (-5035 2385);
PAINT ORANGE (-5035 2385);
FORCEPROP 2 LASTPIN (-5025 2325) $PN V81
J 2
(-5035 2335);
DISPLAY 0.617021 (-5035 2335);
PAINT ORANGE (-5035 2335);
FORCEPROP 2 LASTPIN (-5025 2275) $PN N84
J 2
(-5035 2285);
DISPLAY 0.617021 (-5035 2285);
PAINT ORANGE (-5035 2285);
FORCEPROP 2 LASTPIN (-5025 2225) $PN N86
J 2
(-5035 2235);
DISPLAY 0.617021 (-5035 2235);
PAINT ORANGE (-5035 2235);
FORCEPROP 2 LASTPIN (-5025 2175) $PN AA84
J 2
(-5035 2185);
DISPLAY 0.617021 (-5035 2185);
PAINT ORANGE (-5035 2185);
FORCEPROP 2 LASTPIN (-5025 2125) $PN AA86
J 2
(-5035 2135);
DISPLAY 0.617021 (-5035 2135);
PAINT ORANGE (-5035 2135);
FORCEPROP 2 LASTPIN (-5025 2075) $PN L84
J 2
(-5035 2085);
DISPLAY 0.617021 (-5035 2085);
PAINT ORANGE (-5035 2085);
FORCEPROP 2 LASTPIN (-5025 2025) $PN L86
J 2
(-5035 2035);
DISPLAY 0.617021 (-5035 2035);
PAINT ORANGE (-5035 2035);
FORCEPROP 2 LASTPIN (-5025 1975) $PN W84
J 2
(-5035 1985);
DISPLAY 0.617021 (-5035 1985);
PAINT ORANGE (-5035 1985);
FORCEPROP 2 LASTPIN (-5025 1925) $PN W86
J 2
(-5035 1935);
DISPLAY 0.617021 (-5035 1935);
PAINT ORANGE (-5035 1935);
FORCEPROP 2 LASTPIN (-5025 1875) $PN AG84
J 2
(-5035 1885);
DISPLAY 0.617021 (-5035 1885);
PAINT ORANGE (-5035 1885);
FORCEPROP 2 LASTPIN (-5025 1825) $PN AG86
J 2
(-5035 1835);
DISPLAY 0.617021 (-5035 1835);
PAINT ORANGE (-5035 1835);
FORCEPROP 2 LASTPIN (-5025 1775) $PN AR84
J 2
(-5035 1785);
DISPLAY 0.617021 (-5035 1785);
PAINT ORANGE (-5035 1785);
FORCEPROP 2 LASTPIN (-5025 1725) $PN AR86
J 2
(-5035 1735);
DISPLAY 0.617021 (-5035 1735);
PAINT ORANGE (-5035 1735);
FORCEPROP 2 LASTPIN (-5025 1675) $PN AE84
J 2
(-5035 1685);
DISPLAY 0.617021 (-5035 1685);
PAINT ORANGE (-5035 1685);
FORCEPROP 2 LASTPIN (-5025 1625) $PN AE86
J 2
(-5035 1635);
DISPLAY 0.617021 (-5035 1635);
PAINT ORANGE (-5035 1635);
FORCEPROP 2 LASTPIN (-5025 1575) $PN AN84
J 2
(-5035 1585);
DISPLAY 0.617021 (-5035 1585);
PAINT ORANGE (-5035 1585);
FORCEPROP 2 LASTPIN (-5025 1525) $PN AN86
J 2
(-5035 1535);
DISPLAY 0.617021 (-5035 1535);
PAINT ORANGE (-5035 1535);
FORCEPROP 2 LASTPIN (-3325 1325) $PN K45
J 0
(-3315 1335);
DISPLAY 0.617021 (-3315 1335);
PAINT ORANGE (-3315 1335);
FORCEPROP 2 LASTPIN (-3325 1275) $PN F45
J 0
(-3315 1285);
DISPLAY 0.617021 (-3315 1285);
PAINT ORANGE (-3315 1285);
FORCEPROP 2 LASTPIN (-3325 1225) $PN D49
J 0
(-3315 1235);
DISPLAY 0.617021 (-3315 1235);
PAINT ORANGE (-3315 1235);
FORCEPROP 2 LASTPIN (-3325 1175) $PN B51
J 0
(-3315 1185);
DISPLAY 0.617021 (-3315 1185);
PAINT ORANGE (-3315 1185);
FORCEPROP 2 LASTPIN (-3325 1125) $PN F47
J 0
(-3315 1135);
DISPLAY 0.617021 (-3315 1135);
PAINT ORANGE (-3315 1135);
FORCEPROP 2 LASTPIN (-3325 1075) $PN D47
J 0
(-3315 1085);
DISPLAY 0.617021 (-3315 1085);
PAINT ORANGE (-3315 1085);
FORCEPROP 2 LASTPIN (-3325 1025) $PN F49
J 0
(-3315 1035);
DISPLAY 0.617021 (-3315 1035);
PAINT ORANGE (-3315 1035);
FORCEPROP 2 LASTPIN (-3325 975) $PN G52
J 0
(-3315 985);
DISPLAY 0.617021 (-3315 985);
PAINT ORANGE (-3315 985);
FORCEPROP 2 LASTPIN (-5025 975) $PN B57
J 2
(-5035 985);
DISPLAY 0.617021 (-5035 985);
PAINT ORANGE (-5035 985);
FORCEPROP 2 LASTPIN (-5025 925) $PN G56
J 2
(-5035 935);
DISPLAY 0.617021 (-5035 935);
PAINT ORANGE (-5035 935);
FORCEPROP 2 LASTPIN (-5025 875) $PN B55
J 2
(-5035 885);
DISPLAY 0.617021 (-5035 885);
PAINT ORANGE (-5035 885);
FORCEPROP 2 LASTPIN (-5025 825) $PN D55
J 2
(-5035 835);
DISPLAY 0.617021 (-5035 835);
PAINT ORANGE (-5035 835);
FORCEPROP 2 LASTPIN (-5025 775) $PN C56
J 2
(-5035 785);
DISPLAY 0.617021 (-5035 785);
PAINT ORANGE (-5035 785);
FORCEPROP 2 LASTPIN (-5025 725) $PN J56
J 2
(-5035 735);
DISPLAY 0.617021 (-5035 735);
PAINT ORANGE (-5035 735);
FORCEPROP 2 LASTPIN (-5025 675) $PN C54
J 2
(-5035 685);
DISPLAY 0.617021 (-5035 685);
PAINT ORANGE (-5035 685);
FORCEPROP 2 LASTPIN (-5025 625) $PN F55
J 2
(-5035 635);
DISPLAY 0.617021 (-5035 635);
PAINT ORANGE (-5035 635);
FORCEPROP 2 LASTPIN (-3325 1825) $PN D63
J 0
(-3315 1835);
DISPLAY 0.617021 (-3315 1835);
PAINT ORANGE (-3315 1835);
FORCEPROP 2 LASTPIN (-3325 1775) $PN B63
J 0
(-3315 1785);
DISPLAY 0.617021 (-3315 1785);
PAINT ORANGE (-3315 1785);
FORCEPROP 2 LASTPIN (-3325 1725) $PN C64
J 0
(-3315 1735);
DISPLAY 0.617021 (-3315 1735);
PAINT ORANGE (-3315 1735);
FORCEPROP 2 LASTPIN (-3325 1675) $PN C62
J 0
(-3315 1685);
DISPLAY 0.617021 (-3315 1685);
PAINT ORANGE (-3315 1685);
FORCEPROP 2 LASTPIN (-5025 525) $PN G46
J 2
(-5035 535);
DISPLAY 0.617021 (-5035 535);
PAINT ORANGE (-5035 535);
FORCEPROP 2 LASTPIN (-3325 875) $PN F63
J 0
(-3315 885);
DISPLAY 0.617021 (-3315 885);
PAINT ORANGE (-3315 885);
FORCEPROP 2 LASTPIN (-3325 825) $PN D61
J 0
(-3315 835);
DISPLAY 0.617021 (-3315 835);
PAINT ORANGE (-3315 835);
FORCEPROP 2 LASTPIN (-3325 775) $PN G54
J 0
(-3315 785);
DISPLAY 0.617021 (-3315 785);
PAINT ORANGE (-3315 785);
FORCEPROP 2 LASTPIN (-3325 725) $PN C52
J 0
(-3315 735);
DISPLAY 0.617021 (-3315 735);
PAINT ORANGE (-3315 735);
FORCEPROP 2 LASTPIN (-3325 575) $PN B61
J 0
(-3315 585);
DISPLAY 0.617021 (-3315 585);
PAINT ORANGE (-3315 585);
FORCEPROP 2 LASTPIN (-3325 625) $PN J60
J 0
(-3315 635);
DISPLAY 0.617021 (-3315 635);
PAINT ORANGE (-3315 635);
FORCEPROP 1 LAST PACK_TYPE BGA1
J 0
(-4975 4975);
PAINT SKYBLUE (-4975 4975);
DISPLAY INVISIBLE (-4975 4975);
FORCEPROP 2 LAST SEC_TYPE BGA1
J 0
(-4975 4975);
DISPLAY 1.021277 (-4975 4975);
PAINT ORANGE (-4975 4975);
DISPLAY INVISIBLE (-4975 4975);
FORCEPROP 2 LAST CDS_LIB chpset_lib
J 0
(-4175 2575);
PAINT ORANGE (-4175 2575);
DISPLAY INVISIBLE (-4175 2575);
FORCEPROP 2 LAST SEC 3
J 0
(-4975 4975);
DISPLAY 0.680851 (-4975 4975);
PAINT MONO (-4975 4975);
DISPLAY INVISIBLE (-4975 4975);
FORCEPROP 2 LAST CDS_LOCATION U2D1
J 0
(-4975 4925);
DISPLAY 0.617021 (-4975 4925);
PAINT AQUA (-4975 4925);
DISPLAY INVISIBLE (-4975 4925);
FORCEPROP 1 LAST PATH I172
J 0
(-4175 4875);
PAINT GREEN (-4175 4875);
DISPLAY INVISIBLE (-4175 4875);
FORCEADD TAP..6
(-5575 1325);
FORCEPROP 3 LASTPIN (-5525 1325) SIG_NAME M_G_ECC<5>
J 0
(-5515 1335);
DISPLAY 0.659574 (-5515 1335);
PAINT MONO (-5515 1335);
DISPLAY INVISIBLE (-5515 1335);
FORCEPROP 1 LASTPIN (-5525 1325) BN 5
J 0
(-5577 1333);
DISPLAY 0.617021 (-5577 1333);
PAINT GREEN (-5577 1333);
FORCEPROP 2 LAST CDS_LIB mstr_standard
J 0
(-5575 1325);
PAINT MONO (-5575 1325);
DISPLAY INVISIBLE (-5575 1325);
FORCEPROP 1 LAST BODY_TYPE PLUMBING
J 0
(-5575 1275);
DISPLAY 1.595745 (-5575 1275);
PAINT GREEN (-5575 1275);
DISPLAY INVISIBLE (-5575 1275);
FORCEPROP 1 LAST HDL_TAP TRUE
J 0
(-5250 1200);
DISPLAY 1.595745 (-5250 1200);
PAINT GREEN (-5250 1200);
DISPLAY INVISIBLE (-5250 1200);
FORCEPROP 1 LAST PATH I18
J 0
(-5577 1325);
DISPLAY 0.872340 (-5577 1325);
PAINT GREEN (-5577 1325);
DISPLAY INVISIBLE (-5577 1325);
FORCEADD TAP..6
(-5575 1375);
FORCEPROP 3 LASTPIN (-5525 1375) SIG_NAME M_G_ECC<6>
J 0
(-5515 1385);
DISPLAY 0.659574 (-5515 1385);
PAINT MONO (-5515 1385);
DISPLAY INVISIBLE (-5515 1385);
FORCEPROP 1 LASTPIN (-5525 1375) BN 6
J 0
(-5577 1383);
DISPLAY 0.617021 (-5577 1383);
PAINT GREEN (-5577 1383);
FORCEPROP 2 LAST CDS_LIB mstr_standard
J 0
(-5575 1375);
PAINT MONO (-5575 1375);
DISPLAY INVISIBLE (-5575 1375);
FORCEPROP 1 LAST BODY_TYPE PLUMBING
J 0
(-5575 1325);
DISPLAY 1.595745 (-5575 1325);
PAINT GREEN (-5575 1325);
DISPLAY INVISIBLE (-5575 1325);
FORCEPROP 1 LAST HDL_TAP TRUE
J 0
(-5250 1250);
DISPLAY 1.595745 (-5250 1250);
PAINT GREEN (-5250 1250);
DISPLAY INVISIBLE (-5250 1250);
FORCEPROP 1 LAST PATH I19
J 0
(-5577 1375);
DISPLAY 0.872340 (-5577 1375);
PAINT GREEN (-5577 1375);
DISPLAY INVISIBLE (-5577 1375);
FORCEADD OFFPAGE..5
(-6425 825);
FORCEPROP 2 LAST $XR0 77 
J 0
(-6679 825);
DISPLAY 0.638298 (-6679 825);
PAINT MONO (-6679 825);
FORCEPROP 2 LAST $XR1 78 
J 0
(-6769 825);
DISPLAY 0.638298 (-6769 825);
PAINT MONO (-6769 825);
FORCEPROP 2 LAST CDS_LIB mstr_standard
J 0
(-6425 825);
PAINT MONO (-6425 825);
DISPLAY INVISIBLE (-6425 825);
FORCEPROP 1 LAST OFFPAGE TRUE
J 0
(-6100 700);
DISPLAY 1.170213 (-6100 700);
PAINT GREEN (-6100 700);
DISPLAY INVISIBLE (-6100 700);
FORCEPROP 1 LAST COMMENT_BODY TRUE
J 0
(-6325 750);
DISPLAY 1.170213 (-6325 750);
PAINT GREEN (-6325 750);
DISPLAY INVISIBLE (-6325 750);
FORCEPROP 2 LAST PATH I2
J 0
(-6375 900);
DISPLAY 1.021277 (-6375 900);
PAINT ORANGE (-6375 900);
DISPLAY INVISIBLE (-6375 900);
FORCEADD TAP..6
(-5575 1425);
FORCEPROP 3 LASTPIN (-5525 1425) SIG_NAME M_G_ECC<7>
J 0
(-5515 1435);
DISPLAY 0.659574 (-5515 1435);
PAINT MONO (-5515 1435);
DISPLAY INVISIBLE (-5515 1435);
FORCEPROP 1 LASTPIN (-5525 1425) BN 7
J 0
(-5577 1433);
DISPLAY 0.617021 (-5577 1433);
PAINT GREEN (-5577 1433);
FORCEPROP 2 LAST CDS_LIB mstr_standard
J 0
(-5575 1425);
PAINT MONO (-5575 1425);
DISPLAY INVISIBLE (-5575 1425);
FORCEPROP 1 LAST BODY_TYPE PLUMBING
J 0
(-5575 1375);
DISPLAY 1.595745 (-5575 1375);
PAINT GREEN (-5575 1375);
DISPLAY INVISIBLE (-5575 1375);
FORCEPROP 1 LAST HDL_TAP TRUE
J 0
(-5250 1300);
DISPLAY 1.595745 (-5250 1300);
PAINT GREEN (-5250 1300);
DISPLAY INVISIBLE (-5250 1300);
FORCEPROP 1 LAST PATH I20
J 0
(-5577 1425);
DISPLAY 0.872340 (-5577 1425);
PAINT GREEN (-5577 1425);
DISPLAY INVISIBLE (-5577 1425);
FORCEADD TAP..6
(-5575 1525);
FORCEPROP 3 LASTPIN (-5525 1525) SIG_NAME M_G_DQ<0>
J 0
(-5515 1535);
DISPLAY 0.659574 (-5515 1535);
PAINT MONO (-5515 1535);
DISPLAY INVISIBLE (-5515 1535);
FORCEPROP 1 LASTPIN (-5525 1525) BN 0
J 0
(-5577 1533);
DISPLAY 0.617021 (-5577 1533);
PAINT GREEN (-5577 1533);
FORCEPROP 2 LAST CDS_LIB mstr_standard
J 0
(-5575 1525);
PAINT MONO (-5575 1525);
DISPLAY INVISIBLE (-5575 1525);
FORCEPROP 1 LAST BODY_TYPE PLUMBING
J 0
(-5575 1475);
DISPLAY 1.595745 (-5575 1475);
PAINT GREEN (-5575 1475);
DISPLAY INVISIBLE (-5575 1475);
FORCEPROP 1 LAST HDL_TAP TRUE
J 0
(-5250 1400);
DISPLAY 1.595745 (-5250 1400);
PAINT GREEN (-5250 1400);
DISPLAY INVISIBLE (-5250 1400);
FORCEPROP 1 LAST PATH I21
J 0
(-5577 1525);
DISPLAY 0.872340 (-5577 1525);
PAINT GREEN (-5577 1525);
DISPLAY INVISIBLE (-5577 1525);
FORCEADD TAP..6
(-5575 1575);
FORCEPROP 3 LASTPIN (-5525 1575) SIG_NAME M_G_DQ<1>
J 0
(-5515 1585);
DISPLAY 0.659574 (-5515 1585);
PAINT MONO (-5515 1585);
DISPLAY INVISIBLE (-5515 1585);
FORCEPROP 1 LASTPIN (-5525 1575) BN 1
J 0
(-5577 1583);
DISPLAY 0.617021 (-5577 1583);
PAINT GREEN (-5577 1583);
FORCEPROP 2 LAST CDS_LIB mstr_standard
J 0
(-5575 1575);
PAINT MONO (-5575 1575);
DISPLAY INVISIBLE (-5575 1575);
FORCEPROP 1 LAST BODY_TYPE PLUMBING
J 0
(-5575 1525);
DISPLAY 1.595745 (-5575 1525);
PAINT GREEN (-5575 1525);
DISPLAY INVISIBLE (-5575 1525);
FORCEPROP 1 LAST HDL_TAP TRUE
J 0
(-5250 1450);
DISPLAY 1.595745 (-5250 1450);
PAINT GREEN (-5250 1450);
DISPLAY INVISIBLE (-5250 1450);
FORCEPROP 1 LAST PATH I22
J 0
(-5577 1575);
DISPLAY 0.872340 (-5577 1575);
PAINT GREEN (-5577 1575);
DISPLAY INVISIBLE (-5577 1575);
FORCEADD TAP..6
(-5575 1625);
FORCEPROP 3 LASTPIN (-5525 1625) SIG_NAME M_G_DQ<2>
J 0
(-5515 1635);
DISPLAY 0.659574 (-5515 1635);
PAINT MONO (-5515 1635);
DISPLAY INVISIBLE (-5515 1635);
FORCEPROP 1 LASTPIN (-5525 1625) BN 2
J 0
(-5577 1633);
DISPLAY 0.617021 (-5577 1633);
PAINT GREEN (-5577 1633);
FORCEPROP 2 LAST CDS_LIB mstr_standard
J 0
(-5575 1625);
PAINT MONO (-5575 1625);
DISPLAY INVISIBLE (-5575 1625);
FORCEPROP 1 LAST BODY_TYPE PLUMBING
J 0
(-5575 1575);
DISPLAY 1.595745 (-5575 1575);
PAINT GREEN (-5575 1575);
DISPLAY INVISIBLE (-5575 1575);
FORCEPROP 1 LAST HDL_TAP TRUE
J 0
(-5250 1500);
DISPLAY 1.595745 (-5250 1500);
PAINT GREEN (-5250 1500);
DISPLAY INVISIBLE (-5250 1500);
FORCEPROP 1 LAST PATH I23
J 0
(-5577 1625);
DISPLAY 0.872340 (-5577 1625);
PAINT GREEN (-5577 1625);
DISPLAY INVISIBLE (-5577 1625);
FORCEADD TAP..6
(-5575 1675);
FORCEPROP 3 LASTPIN (-5525 1675) SIG_NAME M_G_DQ<3>
J 0
(-5515 1685);
DISPLAY 0.659574 (-5515 1685);
PAINT MONO (-5515 1685);
DISPLAY INVISIBLE (-5515 1685);
FORCEPROP 1 LASTPIN (-5525 1675) BN 3
J 0
(-5577 1683);
DISPLAY 0.617021 (-5577 1683);
PAINT GREEN (-5577 1683);
FORCEPROP 2 LAST CDS_LIB mstr_standard
J 0
(-5575 1675);
PAINT MONO (-5575 1675);
DISPLAY INVISIBLE (-5575 1675);
FORCEPROP 1 LAST BODY_TYPE PLUMBING
J 0
(-5575 1625);
DISPLAY 1.595745 (-5575 1625);
PAINT GREEN (-5575 1625);
DISPLAY INVISIBLE (-5575 1625);
FORCEPROP 1 LAST HDL_TAP TRUE
J 0
(-5250 1550);
DISPLAY 1.595745 (-5250 1550);
PAINT GREEN (-5250 1550);
DISPLAY INVISIBLE (-5250 1550);
FORCEPROP 1 LAST PATH I24
J 0
(-5577 1675);
DISPLAY 0.872340 (-5577 1675);
PAINT GREEN (-5577 1675);
DISPLAY INVISIBLE (-5577 1675);
FORCEADD TAP..6
(-5575 1725);
FORCEPROP 3 LASTPIN (-5525 1725) SIG_NAME M_G_DQ<4>
J 0
(-5515 1735);
DISPLAY 0.659574 (-5515 1735);
PAINT MONO (-5515 1735);
DISPLAY INVISIBLE (-5515 1735);
FORCEPROP 1 LASTPIN (-5525 1725) BN 4
J 0
(-5577 1733);
DISPLAY 0.617021 (-5577 1733);
PAINT GREEN (-5577 1733);
FORCEPROP 2 LAST CDS_LIB mstr_standard
J 0
(-5575 1725);
PAINT MONO (-5575 1725);
DISPLAY INVISIBLE (-5575 1725);
FORCEPROP 1 LAST BODY_TYPE PLUMBING
J 0
(-5575 1675);
DISPLAY 1.595745 (-5575 1675);
PAINT GREEN (-5575 1675);
DISPLAY INVISIBLE (-5575 1675);
FORCEPROP 1 LAST HDL_TAP TRUE
J 0
(-5250 1600);
DISPLAY 1.595745 (-5250 1600);
PAINT GREEN (-5250 1600);
DISPLAY INVISIBLE (-5250 1600);
FORCEPROP 1 LAST PATH I25
J 0
(-5577 1725);
DISPLAY 0.872340 (-5577 1725);
PAINT GREEN (-5577 1725);
DISPLAY INVISIBLE (-5577 1725);
FORCEADD TAP..6
(-5575 1775);
FORCEPROP 3 LASTPIN (-5525 1775) SIG_NAME M_G_DQ<5>
J 0
(-5515 1785);
DISPLAY 0.659574 (-5515 1785);
PAINT MONO (-5515 1785);
DISPLAY INVISIBLE (-5515 1785);
FORCEPROP 1 LASTPIN (-5525 1775) BN 5
J 0
(-5577 1783);
DISPLAY 0.617021 (-5577 1783);
PAINT GREEN (-5577 1783);
FORCEPROP 2 LAST CDS_LIB mstr_standard
J 0
(-5575 1775);
PAINT MONO (-5575 1775);
DISPLAY INVISIBLE (-5575 1775);
FORCEPROP 1 LAST BODY_TYPE PLUMBING
J 0
(-5575 1725);
DISPLAY 1.595745 (-5575 1725);
PAINT GREEN (-5575 1725);
DISPLAY INVISIBLE (-5575 1725);
FORCEPROP 1 LAST HDL_TAP TRUE
J 0
(-5250 1650);
DISPLAY 1.595745 (-5250 1650);
PAINT GREEN (-5250 1650);
DISPLAY INVISIBLE (-5250 1650);
FORCEPROP 1 LAST PATH I26
J 0
(-5577 1775);
DISPLAY 0.872340 (-5577 1775);
PAINT GREEN (-5577 1775);
DISPLAY INVISIBLE (-5577 1775);
FORCEADD TAP..6
(-5575 1825);
FORCEPROP 3 LASTPIN (-5525 1825) SIG_NAME M_G_DQ<6>
J 0
(-5515 1835);
DISPLAY 0.659574 (-5515 1835);
PAINT MONO (-5515 1835);
DISPLAY INVISIBLE (-5515 1835);
FORCEPROP 1 LASTPIN (-5525 1825) BN 6
J 0
(-5577 1833);
DISPLAY 0.617021 (-5577 1833);
PAINT GREEN (-5577 1833);
FORCEPROP 2 LAST CDS_LIB mstr_standard
J 0
(-5575 1825);
PAINT MONO (-5575 1825);
DISPLAY INVISIBLE (-5575 1825);
FORCEPROP 1 LAST BODY_TYPE PLUMBING
J 0
(-5575 1775);
DISPLAY 1.595745 (-5575 1775);
PAINT GREEN (-5575 1775);
DISPLAY INVISIBLE (-5575 1775);
FORCEPROP 1 LAST HDL_TAP TRUE
J 0
(-5250 1700);
DISPLAY 1.595745 (-5250 1700);
PAINT GREEN (-5250 1700);
DISPLAY INVISIBLE (-5250 1700);
FORCEPROP 1 LAST PATH I27
J 0
(-5577 1825);
DISPLAY 0.872340 (-5577 1825);
PAINT GREEN (-5577 1825);
DISPLAY INVISIBLE (-5577 1825);
FORCEADD TAP..6
(-5575 1925);
FORCEPROP 3 LASTPIN (-5525 1925) SIG_NAME M_G_DQ<8>
J 0
(-5515 1935);
DISPLAY 0.659574 (-5515 1935);
PAINT MONO (-5515 1935);
DISPLAY INVISIBLE (-5515 1935);
FORCEPROP 1 LASTPIN (-5525 1925) BN 8
J 0
(-5577 1933);
DISPLAY 0.617021 (-5577 1933);
PAINT GREEN (-5577 1933);
FORCEPROP 2 LAST CDS_LIB mstr_standard
J 0
(-5575 1925);
PAINT MONO (-5575 1925);
DISPLAY INVISIBLE (-5575 1925);
FORCEPROP 1 LAST BODY_TYPE PLUMBING
J 0
(-5575 1875);
DISPLAY 1.595745 (-5575 1875);
PAINT GREEN (-5575 1875);
DISPLAY INVISIBLE (-5575 1875);
FORCEPROP 1 LAST HDL_TAP TRUE
J 0
(-5250 1800);
DISPLAY 1.595745 (-5250 1800);
PAINT GREEN (-5250 1800);
DISPLAY INVISIBLE (-5250 1800);
FORCEPROP 1 LAST PATH I28
J 0
(-5577 1925);
DISPLAY 0.872340 (-5577 1925);
PAINT GREEN (-5577 1925);
DISPLAY INVISIBLE (-5577 1925);
FORCEADD TAP..6
(-5575 1875);
FORCEPROP 3 LASTPIN (-5525 1875) SIG_NAME M_G_DQ<7>
J 0
(-5515 1885);
DISPLAY 0.659574 (-5515 1885);
PAINT MONO (-5515 1885);
DISPLAY INVISIBLE (-5515 1885);
FORCEPROP 1 LASTPIN (-5525 1875) BN 7
J 0
(-5577 1883);
DISPLAY 0.617021 (-5577 1883);
PAINT GREEN (-5577 1883);
FORCEPROP 2 LAST CDS_LIB mstr_standard
J 0
(-5575 1875);
PAINT MONO (-5575 1875);
DISPLAY INVISIBLE (-5575 1875);
FORCEPROP 1 LAST BODY_TYPE PLUMBING
J 0
(-5575 1825);
DISPLAY 1.595745 (-5575 1825);
PAINT GREEN (-5575 1825);
DISPLAY INVISIBLE (-5575 1825);
FORCEPROP 1 LAST HDL_TAP TRUE
J 0
(-5250 1750);
DISPLAY 1.595745 (-5250 1750);
PAINT GREEN (-5250 1750);
DISPLAY INVISIBLE (-5250 1750);
FORCEPROP 1 LAST PATH I29
J 0
(-5577 1875);
DISPLAY 0.872340 (-5577 1875);
PAINT GREEN (-5577 1875);
DISPLAY INVISIBLE (-5577 1875);
FORCEADD OFFPAGE..5
(-6425 1025);
FORCEPROP 2 LAST $XR0 77 
J 0
(-6679 1025);
DISPLAY 0.638298 (-6679 1025);
PAINT MONO (-6679 1025);
FORCEPROP 2 LAST $XR1 78 
J 0
(-6769 1025);
DISPLAY 0.638298 (-6769 1025);
PAINT MONO (-6769 1025);
FORCEPROP 2 LAST CDS_LIB mstr_standard
J 0
(-6425 1025);
PAINT MONO (-6425 1025);
DISPLAY INVISIBLE (-6425 1025);
FORCEPROP 1 LAST OFFPAGE TRUE
J 0
(-6100 900);
DISPLAY 1.170213 (-6100 900);
PAINT GREEN (-6100 900);
DISPLAY INVISIBLE (-6100 900);
FORCEPROP 1 LAST COMMENT_BODY TRUE
J 0
(-6325 950);
DISPLAY 1.170213 (-6325 950);
PAINT GREEN (-6325 950);
DISPLAY INVISIBLE (-6325 950);
FORCEPROP 2 LAST PATH I3
J 0
(-6375 1100);
DISPLAY 1.021277 (-6375 1100);
PAINT ORANGE (-6375 1100);
DISPLAY INVISIBLE (-6375 1100);
FORCEADD TAP..6
(-5575 1975);
FORCEPROP 3 LASTPIN (-5525 1975) SIG_NAME M_G_DQ<9>
J 0
(-5515 1985);
DISPLAY 0.659574 (-5515 1985);
PAINT MONO (-5515 1985);
DISPLAY INVISIBLE (-5515 1985);
FORCEPROP 1 LASTPIN (-5525 1975) BN 9
J 0
(-5577 1983);
DISPLAY 0.617021 (-5577 1983);
PAINT GREEN (-5577 1983);
FORCEPROP 2 LAST CDS_LIB mstr_standard
J 0
(-5575 1975);
PAINT MONO (-5575 1975);
DISPLAY INVISIBLE (-5575 1975);
FORCEPROP 1 LAST BODY_TYPE PLUMBING
J 0
(-5575 1925);
DISPLAY 1.595745 (-5575 1925);
PAINT GREEN (-5575 1925);
DISPLAY INVISIBLE (-5575 1925);
FORCEPROP 1 LAST HDL_TAP TRUE
J 0
(-5250 1850);
DISPLAY 1.595745 (-5250 1850);
PAINT GREEN (-5250 1850);
DISPLAY INVISIBLE (-5250 1850);
FORCEPROP 1 LAST PATH I31
J 0
(-5577 1975);
DISPLAY 0.872340 (-5577 1975);
PAINT GREEN (-5577 1975);
DISPLAY INVISIBLE (-5577 1975);
FORCEADD TAP..6
(-5575 2025);
FORCEPROP 3 LASTPIN (-5525 2025) SIG_NAME M_G_DQ<10>
J 0
(-5515 2035);
DISPLAY 0.659574 (-5515 2035);
PAINT MONO (-5515 2035);
DISPLAY INVISIBLE (-5515 2035);
FORCEPROP 1 LASTPIN (-5525 2025) BN 10
J 0
(-5577 2033);
DISPLAY 0.617021 (-5577 2033);
PAINT GREEN (-5577 2033);
FORCEPROP 2 LAST CDS_LIB mstr_standard
J 0
(-5575 2025);
PAINT MONO (-5575 2025);
DISPLAY INVISIBLE (-5575 2025);
FORCEPROP 1 LAST BODY_TYPE PLUMBING
J 0
(-5575 1975);
DISPLAY 1.595745 (-5575 1975);
PAINT GREEN (-5575 1975);
DISPLAY INVISIBLE (-5575 1975);
FORCEPROP 1 LAST HDL_TAP TRUE
J 0
(-5250 1900);
DISPLAY 1.595745 (-5250 1900);
PAINT GREEN (-5250 1900);
DISPLAY INVISIBLE (-5250 1900);
FORCEPROP 1 LAST PATH I32
J 0
(-5577 2025);
DISPLAY 0.872340 (-5577 2025);
PAINT GREEN (-5577 2025);
DISPLAY INVISIBLE (-5577 2025);
FORCEADD TAP..6
(-5575 2075);
FORCEPROP 3 LASTPIN (-5525 2075) SIG_NAME M_G_DQ<11>
J 0
(-5515 2085);
DISPLAY 0.659574 (-5515 2085);
PAINT MONO (-5515 2085);
DISPLAY INVISIBLE (-5515 2085);
FORCEPROP 1 LASTPIN (-5525 2075) BN 11
J 0
(-5577 2083);
DISPLAY 0.617021 (-5577 2083);
PAINT GREEN (-5577 2083);
FORCEPROP 2 LAST CDS_LIB mstr_standard
J 0
(-5575 2075);
PAINT MONO (-5575 2075);
DISPLAY INVISIBLE (-5575 2075);
FORCEPROP 1 LAST BODY_TYPE PLUMBING
J 0
(-5575 2025);
DISPLAY 1.595745 (-5575 2025);
PAINT GREEN (-5575 2025);
DISPLAY INVISIBLE (-5575 2025);
FORCEPROP 1 LAST HDL_TAP TRUE
J 0
(-5250 1950);
DISPLAY 1.595745 (-5250 1950);
PAINT GREEN (-5250 1950);
DISPLAY INVISIBLE (-5250 1950);
FORCEPROP 1 LAST PATH I33
J 0
(-5577 2075);
DISPLAY 0.872340 (-5577 2075);
PAINT GREEN (-5577 2075);
DISPLAY INVISIBLE (-5577 2075);
FORCEADD TAP..6
(-5575 2125);
FORCEPROP 3 LASTPIN (-5525 2125) SIG_NAME M_G_DQ<12>
J 0
(-5515 2135);
DISPLAY 0.659574 (-5515 2135);
PAINT MONO (-5515 2135);
DISPLAY INVISIBLE (-5515 2135);
FORCEPROP 1 LASTPIN (-5525 2125) BN 12
J 0
(-5577 2133);
DISPLAY 0.617021 (-5577 2133);
PAINT GREEN (-5577 2133);
FORCEPROP 2 LAST CDS_LIB mstr_standard
J 0
(-5575 2125);
PAINT MONO (-5575 2125);
DISPLAY INVISIBLE (-5575 2125);
FORCEPROP 1 LAST BODY_TYPE PLUMBING
J 0
(-5575 2075);
DISPLAY 1.595745 (-5575 2075);
PAINT GREEN (-5575 2075);
DISPLAY INVISIBLE (-5575 2075);
FORCEPROP 1 LAST HDL_TAP TRUE
J 0
(-5250 2000);
DISPLAY 1.595745 (-5250 2000);
PAINT GREEN (-5250 2000);
DISPLAY INVISIBLE (-5250 2000);
FORCEPROP 1 LAST PATH I34
J 0
(-5577 2125);
DISPLAY 0.872340 (-5577 2125);
PAINT GREEN (-5577 2125);
DISPLAY INVISIBLE (-5577 2125);
FORCEADD TAP..6
(-5575 2175);
FORCEPROP 3 LASTPIN (-5525 2175) SIG_NAME M_G_DQ<13>
J 0
(-5515 2185);
DISPLAY 0.659574 (-5515 2185);
PAINT MONO (-5515 2185);
DISPLAY INVISIBLE (-5515 2185);
FORCEPROP 1 LASTPIN (-5525 2175) BN 13
J 0
(-5577 2183);
DISPLAY 0.617021 (-5577 2183);
PAINT GREEN (-5577 2183);
FORCEPROP 2 LAST CDS_LIB mstr_standard
J 0
(-5575 2175);
PAINT MONO (-5575 2175);
DISPLAY INVISIBLE (-5575 2175);
FORCEPROP 1 LAST BODY_TYPE PLUMBING
J 0
(-5575 2125);
DISPLAY 1.595745 (-5575 2125);
PAINT GREEN (-5575 2125);
DISPLAY INVISIBLE (-5575 2125);
FORCEPROP 1 LAST HDL_TAP TRUE
J 0
(-5250 2050);
DISPLAY 1.595745 (-5250 2050);
PAINT GREEN (-5250 2050);
DISPLAY INVISIBLE (-5250 2050);
FORCEPROP 1 LAST PATH I35
J 0
(-5577 2175);
DISPLAY 0.872340 (-5577 2175);
PAINT GREEN (-5577 2175);
DISPLAY INVISIBLE (-5577 2175);
FORCEADD TAP..6
(-5575 2225);
FORCEPROP 3 LASTPIN (-5525 2225) SIG_NAME M_G_DQ<14>
J 0
(-5515 2235);
DISPLAY 0.659574 (-5515 2235);
PAINT MONO (-5515 2235);
DISPLAY INVISIBLE (-5515 2235);
FORCEPROP 1 LASTPIN (-5525 2225) BN 14
J 0
(-5577 2233);
DISPLAY 0.617021 (-5577 2233);
PAINT GREEN (-5577 2233);
FORCEPROP 2 LAST CDS_LIB mstr_standard
J 0
(-5575 2225);
PAINT MONO (-5575 2225);
DISPLAY INVISIBLE (-5575 2225);
FORCEPROP 1 LAST BODY_TYPE PLUMBING
J 0
(-5575 2175);
DISPLAY 1.595745 (-5575 2175);
PAINT GREEN (-5575 2175);
DISPLAY INVISIBLE (-5575 2175);
FORCEPROP 1 LAST HDL_TAP TRUE
J 0
(-5250 2100);
DISPLAY 1.595745 (-5250 2100);
PAINT GREEN (-5250 2100);
DISPLAY INVISIBLE (-5250 2100);
FORCEPROP 1 LAST PATH I36
J 0
(-5577 2225);
DISPLAY 0.872340 (-5577 2225);
PAINT GREEN (-5577 2225);
DISPLAY INVISIBLE (-5577 2225);
FORCEADD TAP..6
(-5575 2275);
FORCEPROP 3 LASTPIN (-5525 2275) SIG_NAME M_G_DQ<15>
J 0
(-5515 2285);
DISPLAY 0.659574 (-5515 2285);
PAINT MONO (-5515 2285);
DISPLAY INVISIBLE (-5515 2285);
FORCEPROP 1 LASTPIN (-5525 2275) BN 15
J 0
(-5577 2283);
DISPLAY 0.617021 (-5577 2283);
PAINT GREEN (-5577 2283);
FORCEPROP 2 LAST CDS_LIB mstr_standard
J 0
(-5575 2275);
PAINT MONO (-5575 2275);
DISPLAY INVISIBLE (-5575 2275);
FORCEPROP 1 LAST BODY_TYPE PLUMBING
J 0
(-5575 2225);
DISPLAY 1.595745 (-5575 2225);
PAINT GREEN (-5575 2225);
DISPLAY INVISIBLE (-5575 2225);
FORCEPROP 1 LAST HDL_TAP TRUE
J 0
(-5250 2150);
DISPLAY 1.595745 (-5250 2150);
PAINT GREEN (-5250 2150);
DISPLAY INVISIBLE (-5250 2150);
FORCEPROP 1 LAST PATH I37
J 0
(-5577 2275);
DISPLAY 0.872340 (-5577 2275);
PAINT GREEN (-5577 2275);
DISPLAY INVISIBLE (-5577 2275);
FORCEADD TAP..6
(-5575 2325);
FORCEPROP 3 LASTPIN (-5525 2325) SIG_NAME M_G_DQ<16>
J 0
(-5515 2335);
DISPLAY 0.659574 (-5515 2335);
PAINT MONO (-5515 2335);
DISPLAY INVISIBLE (-5515 2335);
FORCEPROP 1 LASTPIN (-5525 2325) BN 16
J 0
(-5577 2333);
DISPLAY 0.617021 (-5577 2333);
PAINT GREEN (-5577 2333);
FORCEPROP 2 LAST CDS_LIB mstr_standard
J 0
(-5575 2325);
PAINT MONO (-5575 2325);
DISPLAY INVISIBLE (-5575 2325);
FORCEPROP 1 LAST BODY_TYPE PLUMBING
J 0
(-5575 2275);
DISPLAY 1.595745 (-5575 2275);
PAINT GREEN (-5575 2275);
DISPLAY INVISIBLE (-5575 2275);
FORCEPROP 1 LAST HDL_TAP TRUE
J 0
(-5250 2200);
DISPLAY 1.595745 (-5250 2200);
PAINT GREEN (-5250 2200);
DISPLAY INVISIBLE (-5250 2200);
FORCEPROP 1 LAST PATH I38
J 0
(-5577 2325);
DISPLAY 0.872340 (-5577 2325);
PAINT GREEN (-5577 2325);
DISPLAY INVISIBLE (-5577 2325);
FORCEADD TAP..6
(-5575 2375);
FORCEPROP 3 LASTPIN (-5525 2375) SIG_NAME M_G_DQ<17>
J 0
(-5515 2385);
DISPLAY 0.659574 (-5515 2385);
PAINT MONO (-5515 2385);
DISPLAY INVISIBLE (-5515 2385);
FORCEPROP 1 LASTPIN (-5525 2375) BN 17
J 0
(-5577 2383);
DISPLAY 0.617021 (-5577 2383);
PAINT GREEN (-5577 2383);
FORCEPROP 2 LAST CDS_LIB mstr_standard
J 0
(-5575 2375);
PAINT MONO (-5575 2375);
DISPLAY INVISIBLE (-5575 2375);
FORCEPROP 1 LAST BODY_TYPE PLUMBING
J 0
(-5575 2325);
DISPLAY 1.595745 (-5575 2325);
PAINT GREEN (-5575 2325);
DISPLAY INVISIBLE (-5575 2325);
FORCEPROP 1 LAST HDL_TAP TRUE
J 0
(-5250 2250);
DISPLAY 1.595745 (-5250 2250);
PAINT GREEN (-5250 2250);
DISPLAY INVISIBLE (-5250 2250);
FORCEPROP 1 LAST PATH I39
J 0
(-5577 2375);
DISPLAY 0.872340 (-5577 2375);
PAINT GREEN (-5577 2375);
DISPLAY INVISIBLE (-5577 2375);
FORCEADD OFFPAGE..6
(-6425 1475);
FORCEPROP 2 LAST $XR0 77 
J 0
(-6674 1475);
DISPLAY 0.638298 (-6674 1475);
PAINT MONO (-6674 1475);
FORCEPROP 2 LAST $XR1 78 
J 0
(-6764 1475);
DISPLAY 0.638298 (-6764 1475);
PAINT MONO (-6764 1475);
FORCEPROP 2 LAST CDS_LIB mstr_standard
J 0
(-6425 1475);
PAINT MONO (-6425 1475);
DISPLAY INVISIBLE (-6425 1475);
FORCEPROP 1 LAST OFFPAGE TRUE
J 0
(-6100 1350);
DISPLAY 1.170213 (-6100 1350);
PAINT GREEN (-6100 1350);
DISPLAY INVISIBLE (-6100 1350);
FORCEPROP 1 LAST COMMENT_BODY TRUE
J 0
(-6325 1400);
DISPLAY 1.170213 (-6325 1400);
PAINT GREEN (-6325 1400);
DISPLAY INVISIBLE (-6325 1400);
FORCEPROP 2 LAST PATH I4
J 0
(-6375 1550);
DISPLAY 1.021277 (-6375 1550);
PAINT ORANGE (-6375 1550);
DISPLAY INVISIBLE (-6375 1550);
FORCEADD TAP..6
(-5575 2425);
FORCEPROP 3 LASTPIN (-5525 2425) SIG_NAME M_G_DQ<18>
J 0
(-5515 2435);
DISPLAY 0.659574 (-5515 2435);
PAINT MONO (-5515 2435);
DISPLAY INVISIBLE (-5515 2435);
FORCEPROP 1 LASTPIN (-5525 2425) BN 18
J 0
(-5577 2433);
DISPLAY 0.617021 (-5577 2433);
PAINT GREEN (-5577 2433);
FORCEPROP 2 LAST CDS_LIB mstr_standard
J 0
(-5575 2425);
PAINT MONO (-5575 2425);
DISPLAY INVISIBLE (-5575 2425);
FORCEPROP 1 LAST BODY_TYPE PLUMBING
J 0
(-5575 2375);
DISPLAY 1.595745 (-5575 2375);
PAINT GREEN (-5575 2375);
DISPLAY INVISIBLE (-5575 2375);
FORCEPROP 1 LAST HDL_TAP TRUE
J 0
(-5250 2300);
DISPLAY 1.595745 (-5250 2300);
PAINT GREEN (-5250 2300);
DISPLAY INVISIBLE (-5250 2300);
FORCEPROP 1 LAST PATH I40
J 0
(-5577 2425);
DISPLAY 0.872340 (-5577 2425);
PAINT GREEN (-5577 2425);
DISPLAY INVISIBLE (-5577 2425);
FORCEADD TAP..6
(-5575 2475);
FORCEPROP 3 LASTPIN (-5525 2475) SIG_NAME M_G_DQ<19>
J 0
(-5515 2485);
DISPLAY 0.659574 (-5515 2485);
PAINT MONO (-5515 2485);
DISPLAY INVISIBLE (-5515 2485);
FORCEPROP 1 LASTPIN (-5525 2475) BN 19
J 0
(-5577 2483);
DISPLAY 0.617021 (-5577 2483);
PAINT GREEN (-5577 2483);
FORCEPROP 2 LAST CDS_LIB mstr_standard
J 0
(-5575 2475);
PAINT MONO (-5575 2475);
DISPLAY INVISIBLE (-5575 2475);
FORCEPROP 1 LAST BODY_TYPE PLUMBING
J 0
(-5575 2425);
DISPLAY 1.595745 (-5575 2425);
PAINT GREEN (-5575 2425);
DISPLAY INVISIBLE (-5575 2425);
FORCEPROP 1 LAST HDL_TAP TRUE
J 0
(-5250 2350);
DISPLAY 1.595745 (-5250 2350);
PAINT GREEN (-5250 2350);
DISPLAY INVISIBLE (-5250 2350);
FORCEPROP 1 LAST PATH I41
J 0
(-5577 2475);
DISPLAY 0.872340 (-5577 2475);
PAINT GREEN (-5577 2475);
DISPLAY INVISIBLE (-5577 2475);
FORCEADD TAP..6
(-5575 2525);
FORCEPROP 3 LASTPIN (-5525 2525) SIG_NAME M_G_DQ<20>
J 0
(-5515 2535);
DISPLAY 0.659574 (-5515 2535);
PAINT MONO (-5515 2535);
DISPLAY INVISIBLE (-5515 2535);
FORCEPROP 1 LASTPIN (-5525 2525) BN 20
J 0
(-5577 2533);
DISPLAY 0.617021 (-5577 2533);
PAINT GREEN (-5577 2533);
FORCEPROP 2 LAST CDS_LIB mstr_standard
J 0
(-5575 2525);
PAINT MONO (-5575 2525);
DISPLAY INVISIBLE (-5575 2525);
FORCEPROP 1 LAST BODY_TYPE PLUMBING
J 0
(-5575 2475);
DISPLAY 1.595745 (-5575 2475);
PAINT GREEN (-5575 2475);
DISPLAY INVISIBLE (-5575 2475);
FORCEPROP 1 LAST HDL_TAP TRUE
J 0
(-5250 2400);
DISPLAY 1.595745 (-5250 2400);
PAINT GREEN (-5250 2400);
DISPLAY INVISIBLE (-5250 2400);
FORCEPROP 1 LAST PATH I42
J 0
(-5577 2525);
DISPLAY 0.872340 (-5577 2525);
PAINT GREEN (-5577 2525);
DISPLAY INVISIBLE (-5577 2525);
FORCEADD TAP..6
(-5575 2575);
FORCEPROP 3 LASTPIN (-5525 2575) SIG_NAME M_G_DQ<21>
J 0
(-5515 2585);
DISPLAY 0.659574 (-5515 2585);
PAINT MONO (-5515 2585);
DISPLAY INVISIBLE (-5515 2585);
FORCEPROP 1 LASTPIN (-5525 2575) BN 21
J 0
(-5577 2583);
DISPLAY 0.617021 (-5577 2583);
PAINT GREEN (-5577 2583);
FORCEPROP 2 LAST CDS_LIB mstr_standard
J 0
(-5575 2575);
PAINT MONO (-5575 2575);
DISPLAY INVISIBLE (-5575 2575);
FORCEPROP 1 LAST BODY_TYPE PLUMBING
J 0
(-5575 2525);
DISPLAY 1.595745 (-5575 2525);
PAINT GREEN (-5575 2525);
DISPLAY INVISIBLE (-5575 2525);
FORCEPROP 1 LAST HDL_TAP TRUE
J 0
(-5250 2450);
DISPLAY 1.595745 (-5250 2450);
PAINT GREEN (-5250 2450);
DISPLAY INVISIBLE (-5250 2450);
FORCEPROP 1 LAST PATH I43
J 0
(-5577 2575);
DISPLAY 0.872340 (-5577 2575);
PAINT GREEN (-5577 2575);
DISPLAY INVISIBLE (-5577 2575);
FORCEADD TAP..6
(-5575 2625);
FORCEPROP 3 LASTPIN (-5525 2625) SIG_NAME M_G_DQ<22>
J 0
(-5515 2635);
DISPLAY 0.659574 (-5515 2635);
PAINT MONO (-5515 2635);
DISPLAY INVISIBLE (-5515 2635);
FORCEPROP 1 LASTPIN (-5525 2625) BN 22
J 0
(-5577 2633);
DISPLAY 0.617021 (-5577 2633);
PAINT GREEN (-5577 2633);
FORCEPROP 2 LAST CDS_LIB mstr_standard
J 0
(-5575 2625);
PAINT MONO (-5575 2625);
DISPLAY INVISIBLE (-5575 2625);
FORCEPROP 1 LAST BODY_TYPE PLUMBING
J 0
(-5575 2575);
DISPLAY 1.595745 (-5575 2575);
PAINT GREEN (-5575 2575);
DISPLAY INVISIBLE (-5575 2575);
FORCEPROP 1 LAST HDL_TAP TRUE
J 0
(-5250 2500);
DISPLAY 1.595745 (-5250 2500);
PAINT GREEN (-5250 2500);
DISPLAY INVISIBLE (-5250 2500);
FORCEPROP 1 LAST PATH I44
J 0
(-5577 2625);
DISPLAY 0.872340 (-5577 2625);
PAINT GREEN (-5577 2625);
DISPLAY INVISIBLE (-5577 2625);
FORCEADD TAP..6
(-5575 2675);
FORCEPROP 3 LASTPIN (-5525 2675) SIG_NAME M_G_DQ<23>
J 0
(-5515 2685);
DISPLAY 0.659574 (-5515 2685);
PAINT MONO (-5515 2685);
DISPLAY INVISIBLE (-5515 2685);
FORCEPROP 1 LASTPIN (-5525 2675) BN 23
J 0
(-5577 2683);
DISPLAY 0.617021 (-5577 2683);
PAINT GREEN (-5577 2683);
FORCEPROP 2 LAST CDS_LIB mstr_standard
J 0
(-5575 2675);
PAINT MONO (-5575 2675);
DISPLAY INVISIBLE (-5575 2675);
FORCEPROP 1 LAST BODY_TYPE PLUMBING
J 0
(-5575 2625);
DISPLAY 1.595745 (-5575 2625);
PAINT GREEN (-5575 2625);
DISPLAY INVISIBLE (-5575 2625);
FORCEPROP 1 LAST HDL_TAP TRUE
J 0
(-5250 2550);
DISPLAY 1.595745 (-5250 2550);
PAINT GREEN (-5250 2550);
DISPLAY INVISIBLE (-5250 2550);
FORCEPROP 1 LAST PATH I45
J 0
(-5577 2675);
DISPLAY 0.872340 (-5577 2675);
PAINT GREEN (-5577 2675);
DISPLAY INVISIBLE (-5577 2675);
FORCEADD TAP..6
(-5575 2725);
FORCEPROP 3 LASTPIN (-5525 2725) SIG_NAME M_G_DQ<24>
J 0
(-5515 2735);
DISPLAY 0.659574 (-5515 2735);
PAINT MONO (-5515 2735);
DISPLAY INVISIBLE (-5515 2735);
FORCEPROP 1 LASTPIN (-5525 2725) BN 24
J 0
(-5577 2733);
DISPLAY 0.617021 (-5577 2733);
PAINT GREEN (-5577 2733);
FORCEPROP 2 LAST CDS_LIB mstr_standard
J 0
(-5575 2725);
PAINT MONO (-5575 2725);
DISPLAY INVISIBLE (-5575 2725);
FORCEPROP 1 LAST BODY_TYPE PLUMBING
J 0
(-5575 2675);
DISPLAY 1.595745 (-5575 2675);
PAINT GREEN (-5575 2675);
DISPLAY INVISIBLE (-5575 2675);
FORCEPROP 1 LAST HDL_TAP TRUE
J 0
(-5250 2600);
DISPLAY 1.595745 (-5250 2600);
PAINT GREEN (-5250 2600);
DISPLAY INVISIBLE (-5250 2600);
FORCEPROP 1 LAST PATH I46
J 0
(-5577 2725);
DISPLAY 0.872340 (-5577 2725);
PAINT GREEN (-5577 2725);
DISPLAY INVISIBLE (-5577 2725);
FORCEADD TAP..6
(-5575 2825);
FORCEPROP 3 LASTPIN (-5525 2825) SIG_NAME M_G_DQ<26>
J 0
(-5515 2835);
DISPLAY 0.659574 (-5515 2835);
PAINT MONO (-5515 2835);
DISPLAY INVISIBLE (-5515 2835);
FORCEPROP 1 LASTPIN (-5525 2825) BN 26
J 0
(-5577 2833);
DISPLAY 0.617021 (-5577 2833);
PAINT GREEN (-5577 2833);
FORCEPROP 2 LAST CDS_LIB mstr_standard
J 0
(-5575 2825);
PAINT MONO (-5575 2825);
DISPLAY INVISIBLE (-5575 2825);
FORCEPROP 1 LAST BODY_TYPE PLUMBING
J 0
(-5575 2775);
DISPLAY 1.595745 (-5575 2775);
PAINT GREEN (-5575 2775);
DISPLAY INVISIBLE (-5575 2775);
FORCEPROP 1 LAST HDL_TAP TRUE
J 0
(-5250 2700);
DISPLAY 1.595745 (-5250 2700);
PAINT GREEN (-5250 2700);
DISPLAY INVISIBLE (-5250 2700);
FORCEPROP 1 LAST PATH I47
J 0
(-5577 2825);
DISPLAY 0.872340 (-5577 2825);
PAINT GREEN (-5577 2825);
DISPLAY INVISIBLE (-5577 2825);
FORCEADD TAP..6
(-5575 2775);
FORCEPROP 3 LASTPIN (-5525 2775) SIG_NAME M_G_DQ<25>
J 0
(-5515 2785);
DISPLAY 0.659574 (-5515 2785);
PAINT MONO (-5515 2785);
DISPLAY INVISIBLE (-5515 2785);
FORCEPROP 1 LASTPIN (-5525 2775) BN 25
J 0
(-5577 2783);
DISPLAY 0.617021 (-5577 2783);
PAINT GREEN (-5577 2783);
FORCEPROP 2 LAST CDS_LIB mstr_standard
J 0
(-5575 2775);
PAINT MONO (-5575 2775);
DISPLAY INVISIBLE (-5575 2775);
FORCEPROP 1 LAST BODY_TYPE PLUMBING
J 0
(-5575 2725);
DISPLAY 1.595745 (-5575 2725);
PAINT GREEN (-5575 2725);
DISPLAY INVISIBLE (-5575 2725);
FORCEPROP 1 LAST HDL_TAP TRUE
J 0
(-5250 2650);
DISPLAY 1.595745 (-5250 2650);
PAINT GREEN (-5250 2650);
DISPLAY INVISIBLE (-5250 2650);
FORCEPROP 1 LAST PATH I48
J 0
(-5577 2775);
DISPLAY 0.872340 (-5577 2775);
PAINT GREEN (-5577 2775);
DISPLAY INVISIBLE (-5577 2775);
FORCEADD TAP..6
(-5575 2875);
FORCEPROP 3 LASTPIN (-5525 2875) SIG_NAME M_G_DQ<27>
J 0
(-5515 2885);
DISPLAY 0.659574 (-5515 2885);
PAINT MONO (-5515 2885);
DISPLAY INVISIBLE (-5515 2885);
FORCEPROP 1 LASTPIN (-5525 2875) BN 27
J 0
(-5577 2883);
DISPLAY 0.617021 (-5577 2883);
PAINT GREEN (-5577 2883);
FORCEPROP 2 LAST CDS_LIB mstr_standard
J 0
(-5575 2875);
PAINT MONO (-5575 2875);
DISPLAY INVISIBLE (-5575 2875);
FORCEPROP 1 LAST BODY_TYPE PLUMBING
J 0
(-5575 2825);
DISPLAY 1.595745 (-5575 2825);
PAINT GREEN (-5575 2825);
DISPLAY INVISIBLE (-5575 2825);
FORCEPROP 1 LAST HDL_TAP TRUE
J 0
(-5250 2750);
DISPLAY 1.595745 (-5250 2750);
PAINT GREEN (-5250 2750);
DISPLAY INVISIBLE (-5250 2750);
FORCEPROP 1 LAST PATH I49
J 0
(-5577 2875);
DISPLAY 0.872340 (-5577 2875);
PAINT GREEN (-5577 2875);
DISPLAY INVISIBLE (-5577 2875);
FORCEADD TAP..6
(-5575 625);
FORCEPROP 3 LASTPIN (-5525 625) SIG_NAME M_G_CLK_DN<0>
J 0
(-5515 635);
DISPLAY 0.659574 (-5515 635);
PAINT MONO (-5515 635);
DISPLAY INVISIBLE (-5515 635);
FORCEPROP 1 LASTPIN (-5525 625) BN 0
J 0
(-5577 633);
DISPLAY 0.617021 (-5577 633);
PAINT GREEN (-5577 633);
FORCEPROP 2 LAST CDS_LIB mstr_standard
J 0
(-5575 625);
PAINT MONO (-5575 625);
DISPLAY INVISIBLE (-5575 625);
FORCEPROP 1 LAST BODY_TYPE PLUMBING
J 0
(-5575 575);
DISPLAY 1.595745 (-5575 575);
PAINT GREEN (-5575 575);
DISPLAY INVISIBLE (-5575 575);
FORCEPROP 1 LAST HDL_TAP TRUE
J 0
(-5250 500);
DISPLAY 1.595745 (-5250 500);
PAINT GREEN (-5250 500);
DISPLAY INVISIBLE (-5250 500);
FORCEPROP 1 LAST PATH I5
J 0
(-5577 625);
DISPLAY 0.872340 (-5577 625);
PAINT GREEN (-5577 625);
DISPLAY INVISIBLE (-5577 625);
FORCEADD TAP..6
(-5575 2925);
FORCEPROP 3 LASTPIN (-5525 2925) SIG_NAME M_G_DQ<28>
J 0
(-5515 2935);
DISPLAY 0.659574 (-5515 2935);
PAINT MONO (-5515 2935);
DISPLAY INVISIBLE (-5515 2935);
FORCEPROP 1 LASTPIN (-5525 2925) BN 28
J 0
(-5577 2933);
DISPLAY 0.617021 (-5577 2933);
PAINT GREEN (-5577 2933);
FORCEPROP 2 LAST CDS_LIB mstr_standard
J 0
(-5575 2925);
PAINT MONO (-5575 2925);
DISPLAY INVISIBLE (-5575 2925);
FORCEPROP 1 LAST BODY_TYPE PLUMBING
J 0
(-5575 2875);
DISPLAY 1.595745 (-5575 2875);
PAINT GREEN (-5575 2875);
DISPLAY INVISIBLE (-5575 2875);
FORCEPROP 1 LAST HDL_TAP TRUE
J 0
(-5250 2800);
DISPLAY 1.595745 (-5250 2800);
PAINT GREEN (-5250 2800);
DISPLAY INVISIBLE (-5250 2800);
FORCEPROP 1 LAST PATH I50
J 0
(-5577 2925);
DISPLAY 0.872340 (-5577 2925);
PAINT GREEN (-5577 2925);
DISPLAY INVISIBLE (-5577 2925);
FORCEADD TAP..6
(-5575 2975);
FORCEPROP 3 LASTPIN (-5525 2975) SIG_NAME M_G_DQ<29>
J 0
(-5515 2985);
DISPLAY 0.659574 (-5515 2985);
PAINT MONO (-5515 2985);
DISPLAY INVISIBLE (-5515 2985);
FORCEPROP 1 LASTPIN (-5525 2975) BN 29
J 0
(-5577 2983);
DISPLAY 0.617021 (-5577 2983);
PAINT GREEN (-5577 2983);
FORCEPROP 2 LAST CDS_LIB mstr_standard
J 0
(-5575 2975);
PAINT MONO (-5575 2975);
DISPLAY INVISIBLE (-5575 2975);
FORCEPROP 1 LAST BODY_TYPE PLUMBING
J 0
(-5575 2925);
DISPLAY 1.595745 (-5575 2925);
PAINT GREEN (-5575 2925);
DISPLAY INVISIBLE (-5575 2925);
FORCEPROP 1 LAST HDL_TAP TRUE
J 0
(-5250 2850);
DISPLAY 1.595745 (-5250 2850);
PAINT GREEN (-5250 2850);
DISPLAY INVISIBLE (-5250 2850);
FORCEPROP 1 LAST PATH I51
J 0
(-5577 2975);
DISPLAY 0.872340 (-5577 2975);
PAINT GREEN (-5577 2975);
DISPLAY INVISIBLE (-5577 2975);
FORCEADD TAP..6
(-5575 3075);
FORCEPROP 3 LASTPIN (-5525 3075) SIG_NAME M_G_DQ<31>
J 0
(-5515 3085);
DISPLAY 0.659574 (-5515 3085);
PAINT MONO (-5515 3085);
DISPLAY INVISIBLE (-5515 3085);
FORCEPROP 1 LASTPIN (-5525 3075) BN 31
J 0
(-5577 3083);
DISPLAY 0.617021 (-5577 3083);
PAINT GREEN (-5577 3083);
FORCEPROP 2 LAST CDS_LIB mstr_standard
J 0
(-5575 3075);
PAINT MONO (-5575 3075);
DISPLAY INVISIBLE (-5575 3075);
FORCEPROP 1 LAST BODY_TYPE PLUMBING
J 0
(-5575 3025);
DISPLAY 1.595745 (-5575 3025);
PAINT GREEN (-5575 3025);
DISPLAY INVISIBLE (-5575 3025);
FORCEPROP 1 LAST HDL_TAP TRUE
J 0
(-5250 2950);
DISPLAY 1.595745 (-5250 2950);
PAINT GREEN (-5250 2950);
DISPLAY INVISIBLE (-5250 2950);
FORCEPROP 1 LAST PATH I52
J 0
(-5577 3075);
DISPLAY 0.872340 (-5577 3075);
PAINT GREEN (-5577 3075);
DISPLAY INVISIBLE (-5577 3075);
FORCEADD TAP..6
(-5575 3025);
FORCEPROP 3 LASTPIN (-5525 3025) SIG_NAME M_G_DQ<30>
J 0
(-5515 3035);
DISPLAY 0.659574 (-5515 3035);
PAINT MONO (-5515 3035);
DISPLAY INVISIBLE (-5515 3035);
FORCEPROP 1 LASTPIN (-5525 3025) BN 30
J 0
(-5577 3033);
DISPLAY 0.617021 (-5577 3033);
PAINT GREEN (-5577 3033);
FORCEPROP 2 LAST CDS_LIB mstr_standard
J 0
(-5575 3025);
PAINT MONO (-5575 3025);
DISPLAY INVISIBLE (-5575 3025);
FORCEPROP 1 LAST BODY_TYPE PLUMBING
J 0
(-5575 2975);
DISPLAY 1.595745 (-5575 2975);
PAINT GREEN (-5575 2975);
DISPLAY INVISIBLE (-5575 2975);
FORCEPROP 1 LAST HDL_TAP TRUE
J 0
(-5250 2900);
DISPLAY 1.595745 (-5250 2900);
PAINT GREEN (-5250 2900);
DISPLAY INVISIBLE (-5250 2900);
FORCEPROP 1 LAST PATH I53
J 0
(-5577 3025);
DISPLAY 0.872340 (-5577 3025);
PAINT GREEN (-5577 3025);
DISPLAY INVISIBLE (-5577 3025);
FORCEADD TAP..6
(-5575 3125);
FORCEPROP 3 LASTPIN (-5525 3125) SIG_NAME M_G_DQ<32>
J 0
(-5515 3135);
DISPLAY 0.659574 (-5515 3135);
PAINT MONO (-5515 3135);
DISPLAY INVISIBLE (-5515 3135);
FORCEPROP 1 LASTPIN (-5525 3125) BN 32
J 0
(-5577 3133);
DISPLAY 0.617021 (-5577 3133);
PAINT GREEN (-5577 3133);
FORCEPROP 2 LAST CDS_LIB mstr_standard
J 0
(-5575 3125);
PAINT MONO (-5575 3125);
DISPLAY INVISIBLE (-5575 3125);
FORCEPROP 1 LAST BODY_TYPE PLUMBING
J 0
(-5575 3075);
DISPLAY 1.595745 (-5575 3075);
PAINT GREEN (-5575 3075);
DISPLAY INVISIBLE (-5575 3075);
FORCEPROP 1 LAST HDL_TAP TRUE
J 0
(-5250 3000);
DISPLAY 1.595745 (-5250 3000);
PAINT GREEN (-5250 3000);
DISPLAY INVISIBLE (-5250 3000);
FORCEPROP 1 LAST PATH I54
J 0
(-5577 3125);
DISPLAY 0.872340 (-5577 3125);
PAINT GREEN (-5577 3125);
DISPLAY INVISIBLE (-5577 3125);
FORCEADD TAP..6
(-5575 3175);
FORCEPROP 3 LASTPIN (-5525 3175) SIG_NAME M_G_DQ<33>
J 0
(-5515 3185);
DISPLAY 0.659574 (-5515 3185);
PAINT MONO (-5515 3185);
DISPLAY INVISIBLE (-5515 3185);
FORCEPROP 1 LASTPIN (-5525 3175) BN 33
J 0
(-5577 3183);
DISPLAY 0.617021 (-5577 3183);
PAINT GREEN (-5577 3183);
FORCEPROP 2 LAST CDS_LIB mstr_standard
J 0
(-5575 3175);
PAINT MONO (-5575 3175);
DISPLAY INVISIBLE (-5575 3175);
FORCEPROP 1 LAST BODY_TYPE PLUMBING
J 0
(-5575 3125);
DISPLAY 1.595745 (-5575 3125);
PAINT GREEN (-5575 3125);
DISPLAY INVISIBLE (-5575 3125);
FORCEPROP 1 LAST HDL_TAP TRUE
J 0
(-5250 3050);
DISPLAY 1.595745 (-5250 3050);
PAINT GREEN (-5250 3050);
DISPLAY INVISIBLE (-5250 3050);
FORCEPROP 1 LAST PATH I55
J 0
(-5577 3175);
DISPLAY 0.872340 (-5577 3175);
PAINT GREEN (-5577 3175);
DISPLAY INVISIBLE (-5577 3175);
FORCEADD TAP..6
(-5575 3225);
FORCEPROP 3 LASTPIN (-5525 3225) SIG_NAME M_G_DQ<34>
J 0
(-5515 3235);
DISPLAY 0.659574 (-5515 3235);
PAINT MONO (-5515 3235);
DISPLAY INVISIBLE (-5515 3235);
FORCEPROP 1 LASTPIN (-5525 3225) BN 34
J 0
(-5577 3233);
DISPLAY 0.617021 (-5577 3233);
PAINT GREEN (-5577 3233);
FORCEPROP 2 LAST CDS_LIB mstr_standard
J 0
(-5575 3225);
PAINT MONO (-5575 3225);
DISPLAY INVISIBLE (-5575 3225);
FORCEPROP 1 LAST BODY_TYPE PLUMBING
J 0
(-5575 3175);
DISPLAY 1.595745 (-5575 3175);
PAINT GREEN (-5575 3175);
DISPLAY INVISIBLE (-5575 3175);
FORCEPROP 1 LAST HDL_TAP TRUE
J 0
(-5250 3100);
DISPLAY 1.595745 (-5250 3100);
PAINT GREEN (-5250 3100);
DISPLAY INVISIBLE (-5250 3100);
FORCEPROP 1 LAST PATH I56
J 0
(-5577 3225);
DISPLAY 0.872340 (-5577 3225);
PAINT GREEN (-5577 3225);
DISPLAY INVISIBLE (-5577 3225);
FORCEADD TAP..6
(-5575 3325);
FORCEPROP 3 LASTPIN (-5525 3325) SIG_NAME M_G_DQ<36>
J 0
(-5515 3335);
DISPLAY 0.659574 (-5515 3335);
PAINT MONO (-5515 3335);
DISPLAY INVISIBLE (-5515 3335);
FORCEPROP 1 LASTPIN (-5525 3325) BN 36
J 0
(-5577 3333);
DISPLAY 0.617021 (-5577 3333);
PAINT GREEN (-5577 3333);
FORCEPROP 2 LAST CDS_LIB mstr_standard
J 0
(-5575 3325);
PAINT MONO (-5575 3325);
DISPLAY INVISIBLE (-5575 3325);
FORCEPROP 1 LAST BODY_TYPE PLUMBING
J 0
(-5575 3275);
DISPLAY 1.595745 (-5575 3275);
PAINT GREEN (-5575 3275);
DISPLAY INVISIBLE (-5575 3275);
FORCEPROP 1 LAST HDL_TAP TRUE
J 0
(-5250 3200);
DISPLAY 1.595745 (-5250 3200);
PAINT GREEN (-5250 3200);
DISPLAY INVISIBLE (-5250 3200);
FORCEPROP 1 LAST PATH I57
J 0
(-5577 3325);
DISPLAY 0.872340 (-5577 3325);
PAINT GREEN (-5577 3325);
DISPLAY INVISIBLE (-5577 3325);
FORCEADD TAP..6
(-5575 3275);
FORCEPROP 3 LASTPIN (-5525 3275) SIG_NAME M_G_DQ<35>
J 0
(-5515 3285);
DISPLAY 0.659574 (-5515 3285);
PAINT MONO (-5515 3285);
DISPLAY INVISIBLE (-5515 3285);
FORCEPROP 1 LASTPIN (-5525 3275) BN 35
J 0
(-5577 3283);
DISPLAY 0.617021 (-5577 3283);
PAINT GREEN (-5577 3283);
FORCEPROP 2 LAST CDS_LIB mstr_standard
J 0
(-5575 3275);
PAINT MONO (-5575 3275);
DISPLAY INVISIBLE (-5575 3275);
FORCEPROP 1 LAST BODY_TYPE PLUMBING
J 0
(-5575 3225);
DISPLAY 1.595745 (-5575 3225);
PAINT GREEN (-5575 3225);
DISPLAY INVISIBLE (-5575 3225);
FORCEPROP 1 LAST HDL_TAP TRUE
J 0
(-5250 3150);
DISPLAY 1.595745 (-5250 3150);
PAINT GREEN (-5250 3150);
DISPLAY INVISIBLE (-5250 3150);
FORCEPROP 1 LAST PATH I58
J 0
(-5577 3275);
DISPLAY 0.872340 (-5577 3275);
PAINT GREEN (-5577 3275);
DISPLAY INVISIBLE (-5577 3275);
FORCEADD TAP..6
(-5575 3375);
FORCEPROP 3 LASTPIN (-5525 3375) SIG_NAME M_G_DQ<37>
J 0
(-5515 3385);
DISPLAY 0.659574 (-5515 3385);
PAINT MONO (-5515 3385);
DISPLAY INVISIBLE (-5515 3385);
FORCEPROP 1 LASTPIN (-5525 3375) BN 37
J 0
(-5577 3383);
DISPLAY 0.617021 (-5577 3383);
PAINT GREEN (-5577 3383);
FORCEPROP 2 LAST CDS_LIB mstr_standard
J 0
(-5575 3375);
PAINT MONO (-5575 3375);
DISPLAY INVISIBLE (-5575 3375);
FORCEPROP 1 LAST BODY_TYPE PLUMBING
J 0
(-5575 3325);
DISPLAY 1.595745 (-5575 3325);
PAINT GREEN (-5575 3325);
DISPLAY INVISIBLE (-5575 3325);
FORCEPROP 1 LAST HDL_TAP TRUE
J 0
(-5250 3250);
DISPLAY 1.595745 (-5250 3250);
PAINT GREEN (-5250 3250);
DISPLAY INVISIBLE (-5250 3250);
FORCEPROP 1 LAST PATH I59
J 0
(-5577 3375);
DISPLAY 0.872340 (-5577 3375);
PAINT GREEN (-5577 3375);
DISPLAY INVISIBLE (-5577 3375);
FORCEADD TAP..6
(-5575 675);
FORCEPROP 3 LASTPIN (-5525 675) SIG_NAME M_G_CLK_DN<1>
J 0
(-5515 685);
DISPLAY 0.659574 (-5515 685);
PAINT MONO (-5515 685);
DISPLAY INVISIBLE (-5515 685);
FORCEPROP 1 LASTPIN (-5525 675) BN 1
J 0
(-5577 683);
DISPLAY 0.617021 (-5577 683);
PAINT GREEN (-5577 683);
FORCEPROP 2 LAST CDS_LIB mstr_standard
J 0
(-5575 675);
PAINT MONO (-5575 675);
DISPLAY INVISIBLE (-5575 675);
FORCEPROP 1 LAST BODY_TYPE PLUMBING
J 0
(-5575 625);
DISPLAY 1.595745 (-5575 625);
PAINT GREEN (-5575 625);
DISPLAY INVISIBLE (-5575 625);
FORCEPROP 1 LAST HDL_TAP TRUE
J 0
(-5250 550);
DISPLAY 1.595745 (-5250 550);
PAINT GREEN (-5250 550);
DISPLAY INVISIBLE (-5250 550);
FORCEPROP 1 LAST PATH I6
J 0
(-5577 675);
DISPLAY 0.872340 (-5577 675);
PAINT GREEN (-5577 675);
DISPLAY INVISIBLE (-5577 675);
FORCEADD TAP..6
(-5575 3425);
FORCEPROP 3 LASTPIN (-5525 3425) SIG_NAME M_G_DQ<38>
J 0
(-5515 3435);
DISPLAY 0.659574 (-5515 3435);
PAINT MONO (-5515 3435);
DISPLAY INVISIBLE (-5515 3435);
FORCEPROP 1 LASTPIN (-5525 3425) BN 38
J 0
(-5577 3433);
DISPLAY 0.617021 (-5577 3433);
PAINT GREEN (-5577 3433);
FORCEPROP 2 LAST CDS_LIB mstr_standard
J 0
(-5575 3425);
PAINT MONO (-5575 3425);
DISPLAY INVISIBLE (-5575 3425);
FORCEPROP 1 LAST BODY_TYPE PLUMBING
J 0
(-5575 3375);
DISPLAY 1.595745 (-5575 3375);
PAINT GREEN (-5575 3375);
DISPLAY INVISIBLE (-5575 3375);
FORCEPROP 1 LAST HDL_TAP TRUE
J 0
(-5250 3300);
DISPLAY 1.595745 (-5250 3300);
PAINT GREEN (-5250 3300);
DISPLAY INVISIBLE (-5250 3300);
FORCEPROP 1 LAST PATH I60
J 0
(-5577 3425);
DISPLAY 0.872340 (-5577 3425);
PAINT GREEN (-5577 3425);
DISPLAY INVISIBLE (-5577 3425);
FORCEADD TAP..6
(-5575 3475);
FORCEPROP 3 LASTPIN (-5525 3475) SIG_NAME M_G_DQ<39>
J 0
(-5515 3485);
DISPLAY 0.659574 (-5515 3485);
PAINT MONO (-5515 3485);
DISPLAY INVISIBLE (-5515 3485);
FORCEPROP 1 LASTPIN (-5525 3475) BN 39
J 0
(-5577 3483);
DISPLAY 0.617021 (-5577 3483);
PAINT GREEN (-5577 3483);
FORCEPROP 2 LAST CDS_LIB mstr_standard
J 0
(-5575 3475);
PAINT MONO (-5575 3475);
DISPLAY INVISIBLE (-5575 3475);
FORCEPROP 1 LAST BODY_TYPE PLUMBING
J 0
(-5575 3425);
DISPLAY 1.595745 (-5575 3425);
PAINT GREEN (-5575 3425);
DISPLAY INVISIBLE (-5575 3425);
FORCEPROP 1 LAST HDL_TAP TRUE
J 0
(-5250 3350);
DISPLAY 1.595745 (-5250 3350);
PAINT GREEN (-5250 3350);
DISPLAY INVISIBLE (-5250 3350);
FORCEPROP 1 LAST PATH I61
J 0
(-5577 3475);
DISPLAY 0.872340 (-5577 3475);
PAINT GREEN (-5577 3475);
DISPLAY INVISIBLE (-5577 3475);
FORCEADD TAP..6
(-5575 3525);
FORCEPROP 3 LASTPIN (-5525 3525) SIG_NAME M_G_DQ<40>
J 0
(-5515 3535);
DISPLAY 0.659574 (-5515 3535);
PAINT MONO (-5515 3535);
DISPLAY INVISIBLE (-5515 3535);
FORCEPROP 1 LASTPIN (-5525 3525) BN 40
J 0
(-5577 3533);
DISPLAY 0.617021 (-5577 3533);
PAINT GREEN (-5577 3533);
FORCEPROP 2 LAST CDS_LIB mstr_standard
J 0
(-5575 3525);
PAINT MONO (-5575 3525);
DISPLAY INVISIBLE (-5575 3525);
FORCEPROP 1 LAST BODY_TYPE PLUMBING
J 0
(-5575 3475);
DISPLAY 1.595745 (-5575 3475);
PAINT GREEN (-5575 3475);
DISPLAY INVISIBLE (-5575 3475);
FORCEPROP 1 LAST HDL_TAP TRUE
J 0
(-5250 3400);
DISPLAY 1.595745 (-5250 3400);
PAINT GREEN (-5250 3400);
DISPLAY INVISIBLE (-5250 3400);
FORCEPROP 1 LAST PATH I62
J 0
(-5577 3525);
DISPLAY 0.872340 (-5577 3525);
PAINT GREEN (-5577 3525);
DISPLAY INVISIBLE (-5577 3525);
FORCEADD TAP..6
(-5575 3575);
FORCEPROP 3 LASTPIN (-5525 3575) SIG_NAME M_G_DQ<41>
J 0
(-5515 3585);
DISPLAY 0.659574 (-5515 3585);
PAINT MONO (-5515 3585);
DISPLAY INVISIBLE (-5515 3585);
FORCEPROP 1 LASTPIN (-5525 3575) BN 41
J 0
(-5577 3583);
DISPLAY 0.617021 (-5577 3583);
PAINT GREEN (-5577 3583);
FORCEPROP 2 LAST CDS_LIB mstr_standard
J 0
(-5575 3575);
PAINT MONO (-5575 3575);
DISPLAY INVISIBLE (-5575 3575);
FORCEPROP 1 LAST BODY_TYPE PLUMBING
J 0
(-5575 3525);
DISPLAY 1.595745 (-5575 3525);
PAINT GREEN (-5575 3525);
DISPLAY INVISIBLE (-5575 3525);
FORCEPROP 1 LAST HDL_TAP TRUE
J 0
(-5250 3450);
DISPLAY 1.595745 (-5250 3450);
PAINT GREEN (-5250 3450);
DISPLAY INVISIBLE (-5250 3450);
FORCEPROP 1 LAST PATH I63
J 0
(-5577 3575);
DISPLAY 0.872340 (-5577 3575);
PAINT GREEN (-5577 3575);
DISPLAY INVISIBLE (-5577 3575);
FORCEADD TAP..6
(-5575 3625);
FORCEPROP 3 LASTPIN (-5525 3625) SIG_NAME M_G_DQ<42>
J 0
(-5515 3635);
DISPLAY 0.659574 (-5515 3635);
PAINT MONO (-5515 3635);
DISPLAY INVISIBLE (-5515 3635);
FORCEPROP 1 LASTPIN (-5525 3625) BN 42
J 0
(-5577 3633);
DISPLAY 0.617021 (-5577 3633);
PAINT GREEN (-5577 3633);
FORCEPROP 2 LAST CDS_LIB mstr_standard
J 0
(-5575 3625);
PAINT MONO (-5575 3625);
DISPLAY INVISIBLE (-5575 3625);
FORCEPROP 1 LAST BODY_TYPE PLUMBING
J 0
(-5575 3575);
DISPLAY 1.595745 (-5575 3575);
PAINT GREEN (-5575 3575);
DISPLAY INVISIBLE (-5575 3575);
FORCEPROP 1 LAST HDL_TAP TRUE
J 0
(-5250 3500);
DISPLAY 1.595745 (-5250 3500);
PAINT GREEN (-5250 3500);
DISPLAY INVISIBLE (-5250 3500);
FORCEPROP 1 LAST PATH I64
J 0
(-5577 3625);
DISPLAY 0.872340 (-5577 3625);
PAINT GREEN (-5577 3625);
DISPLAY INVISIBLE (-5577 3625);
FORCEADD TAP..6
(-5575 3675);
FORCEPROP 3 LASTPIN (-5525 3675) SIG_NAME M_G_DQ<43>
J 0
(-5515 3685);
DISPLAY 0.659574 (-5515 3685);
PAINT MONO (-5515 3685);
DISPLAY INVISIBLE (-5515 3685);
FORCEPROP 1 LASTPIN (-5525 3675) BN 43
J 0
(-5577 3683);
DISPLAY 0.617021 (-5577 3683);
PAINT GREEN (-5577 3683);
FORCEPROP 2 LAST CDS_LIB mstr_standard
J 0
(-5575 3675);
PAINT MONO (-5575 3675);
DISPLAY INVISIBLE (-5575 3675);
FORCEPROP 1 LAST BODY_TYPE PLUMBING
J 0
(-5575 3625);
DISPLAY 1.595745 (-5575 3625);
PAINT GREEN (-5575 3625);
DISPLAY INVISIBLE (-5575 3625);
FORCEPROP 1 LAST HDL_TAP TRUE
J 0
(-5250 3550);
DISPLAY 1.595745 (-5250 3550);
PAINT GREEN (-5250 3550);
DISPLAY INVISIBLE (-5250 3550);
FORCEPROP 1 LAST PATH I65
J 0
(-5577 3675);
DISPLAY 0.872340 (-5577 3675);
PAINT GREEN (-5577 3675);
DISPLAY INVISIBLE (-5577 3675);
FORCEADD TAP..6
(-5575 3725);
FORCEPROP 3 LASTPIN (-5525 3725) SIG_NAME M_G_DQ<44>
J 0
(-5515 3735);
DISPLAY 0.659574 (-5515 3735);
PAINT MONO (-5515 3735);
DISPLAY INVISIBLE (-5515 3735);
FORCEPROP 1 LASTPIN (-5525 3725) BN 44
J 0
(-5577 3733);
DISPLAY 0.617021 (-5577 3733);
PAINT GREEN (-5577 3733);
FORCEPROP 2 LAST CDS_LIB mstr_standard
J 0
(-5575 3725);
PAINT MONO (-5575 3725);
DISPLAY INVISIBLE (-5575 3725);
FORCEPROP 1 LAST BODY_TYPE PLUMBING
J 0
(-5575 3675);
DISPLAY 1.595745 (-5575 3675);
PAINT GREEN (-5575 3675);
DISPLAY INVISIBLE (-5575 3675);
FORCEPROP 1 LAST HDL_TAP TRUE
J 0
(-5250 3600);
DISPLAY 1.595745 (-5250 3600);
PAINT GREEN (-5250 3600);
DISPLAY INVISIBLE (-5250 3600);
FORCEPROP 1 LAST PATH I66
J 0
(-5577 3725);
DISPLAY 0.872340 (-5577 3725);
PAINT GREEN (-5577 3725);
DISPLAY INVISIBLE (-5577 3725);
FORCEADD TAP..6
(-5575 3775);
FORCEPROP 3 LASTPIN (-5525 3775) SIG_NAME M_G_DQ<45>
J 0
(-5515 3785);
DISPLAY 0.659574 (-5515 3785);
PAINT MONO (-5515 3785);
DISPLAY INVISIBLE (-5515 3785);
FORCEPROP 1 LASTPIN (-5525 3775) BN 45
J 0
(-5577 3783);
DISPLAY 0.617021 (-5577 3783);
PAINT GREEN (-5577 3783);
FORCEPROP 2 LAST CDS_LIB mstr_standard
J 0
(-5575 3775);
PAINT MONO (-5575 3775);
DISPLAY INVISIBLE (-5575 3775);
FORCEPROP 1 LAST BODY_TYPE PLUMBING
J 0
(-5575 3725);
DISPLAY 1.595745 (-5575 3725);
PAINT GREEN (-5575 3725);
DISPLAY INVISIBLE (-5575 3725);
FORCEPROP 1 LAST HDL_TAP TRUE
J 0
(-5250 3650);
DISPLAY 1.595745 (-5250 3650);
PAINT GREEN (-5250 3650);
DISPLAY INVISIBLE (-5250 3650);
FORCEPROP 1 LAST PATH I67
J 0
(-5577 3775);
DISPLAY 0.872340 (-5577 3775);
PAINT GREEN (-5577 3775);
DISPLAY INVISIBLE (-5577 3775);
FORCEADD TAP..6
(-5575 3825);
FORCEPROP 3 LASTPIN (-5525 3825) SIG_NAME M_G_DQ<46>
J 0
(-5515 3835);
DISPLAY 0.659574 (-5515 3835);
PAINT MONO (-5515 3835);
DISPLAY INVISIBLE (-5515 3835);
FORCEPROP 1 LASTPIN (-5525 3825) BN 46
J 0
(-5577 3833);
DISPLAY 0.617021 (-5577 3833);
PAINT GREEN (-5577 3833);
FORCEPROP 2 LAST CDS_LIB mstr_standard
J 0
(-5575 3825);
PAINT MONO (-5575 3825);
DISPLAY INVISIBLE (-5575 3825);
FORCEPROP 1 LAST BODY_TYPE PLUMBING
J 0
(-5575 3775);
DISPLAY 1.595745 (-5575 3775);
PAINT GREEN (-5575 3775);
DISPLAY INVISIBLE (-5575 3775);
FORCEPROP 1 LAST HDL_TAP TRUE
J 0
(-5250 3700);
DISPLAY 1.595745 (-5250 3700);
PAINT GREEN (-5250 3700);
DISPLAY INVISIBLE (-5250 3700);
FORCEPROP 1 LAST PATH I68
J 0
(-5577 3825);
DISPLAY 0.872340 (-5577 3825);
PAINT GREEN (-5577 3825);
DISPLAY INVISIBLE (-5577 3825);
FORCEADD TAP..6
(-5575 3875);
FORCEPROP 3 LASTPIN (-5525 3875) SIG_NAME M_G_DQ<47>
J 0
(-5515 3885);
DISPLAY 0.659574 (-5515 3885);
PAINT MONO (-5515 3885);
DISPLAY INVISIBLE (-5515 3885);
FORCEPROP 1 LASTPIN (-5525 3875) BN 47
J 0
(-5577 3883);
DISPLAY 0.617021 (-5577 3883);
PAINT GREEN (-5577 3883);
FORCEPROP 2 LAST CDS_LIB mstr_standard
J 0
(-5575 3875);
PAINT MONO (-5575 3875);
DISPLAY INVISIBLE (-5575 3875);
FORCEPROP 1 LAST BODY_TYPE PLUMBING
J 0
(-5575 3825);
DISPLAY 1.595745 (-5575 3825);
PAINT GREEN (-5575 3825);
DISPLAY INVISIBLE (-5575 3825);
FORCEPROP 1 LAST HDL_TAP TRUE
J 0
(-5250 3750);
DISPLAY 1.595745 (-5250 3750);
PAINT GREEN (-5250 3750);
DISPLAY INVISIBLE (-5250 3750);
FORCEPROP 1 LAST PATH I69
J 0
(-5577 3875);
DISPLAY 0.872340 (-5577 3875);
PAINT GREEN (-5577 3875);
DISPLAY INVISIBLE (-5577 3875);
FORCEADD TAP..6
(-5575 775);
FORCEPROP 3 LASTPIN (-5525 775) SIG_NAME M_G_CLK_DN<3>
J 0
(-5515 785);
DISPLAY 0.659574 (-5515 785);
PAINT MONO (-5515 785);
DISPLAY INVISIBLE (-5515 785);
FORCEPROP 1 LASTPIN (-5525 775) BN 3
J 0
(-5577 783);
DISPLAY 0.617021 (-5577 783);
PAINT GREEN (-5577 783);
FORCEPROP 2 LAST CDS_LIB mstr_standard
J 0
(-5575 775);
PAINT MONO (-5575 775);
DISPLAY INVISIBLE (-5575 775);
FORCEPROP 1 LAST BODY_TYPE PLUMBING
J 0
(-5575 725);
DISPLAY 1.595745 (-5575 725);
PAINT GREEN (-5575 725);
DISPLAY INVISIBLE (-5575 725);
FORCEPROP 1 LAST HDL_TAP TRUE
J 0
(-5250 650);
DISPLAY 1.595745 (-5250 650);
PAINT GREEN (-5250 650);
DISPLAY INVISIBLE (-5250 650);
FORCEPROP 1 LAST PATH I7
J 0
(-5577 775);
DISPLAY 0.872340 (-5577 775);
PAINT GREEN (-5577 775);
DISPLAY INVISIBLE (-5577 775);
FORCEADD TAP..6
(-5575 3925);
FORCEPROP 3 LASTPIN (-5525 3925) SIG_NAME M_G_DQ<48>
J 0
(-5515 3935);
DISPLAY 0.659574 (-5515 3935);
PAINT MONO (-5515 3935);
DISPLAY INVISIBLE (-5515 3935);
FORCEPROP 1 LASTPIN (-5525 3925) BN 48
J 0
(-5577 3933);
DISPLAY 0.617021 (-5577 3933);
PAINT GREEN (-5577 3933);
FORCEPROP 2 LAST CDS_LIB mstr_standard
J 0
(-5575 3925);
PAINT MONO (-5575 3925);
DISPLAY INVISIBLE (-5575 3925);
FORCEPROP 1 LAST BODY_TYPE PLUMBING
J 0
(-5575 3875);
DISPLAY 1.595745 (-5575 3875);
PAINT GREEN (-5575 3875);
DISPLAY INVISIBLE (-5575 3875);
FORCEPROP 1 LAST HDL_TAP TRUE
J 0
(-5250 3800);
DISPLAY 1.595745 (-5250 3800);
PAINT GREEN (-5250 3800);
DISPLAY INVISIBLE (-5250 3800);
FORCEPROP 1 LAST PATH I70
J 0
(-5577 3925);
DISPLAY 0.872340 (-5577 3925);
PAINT GREEN (-5577 3925);
DISPLAY INVISIBLE (-5577 3925);
FORCEADD TAP..6
(-5575 3975);
FORCEPROP 3 LASTPIN (-5525 3975) SIG_NAME M_G_DQ<49>
J 0
(-5515 3985);
DISPLAY 0.659574 (-5515 3985);
PAINT MONO (-5515 3985);
DISPLAY INVISIBLE (-5515 3985);
FORCEPROP 1 LASTPIN (-5525 3975) BN 49
J 0
(-5577 3983);
DISPLAY 0.617021 (-5577 3983);
PAINT GREEN (-5577 3983);
FORCEPROP 2 LAST CDS_LIB mstr_standard
J 0
(-5575 3975);
PAINT MONO (-5575 3975);
DISPLAY INVISIBLE (-5575 3975);
FORCEPROP 1 LAST BODY_TYPE PLUMBING
J 0
(-5575 3925);
DISPLAY 1.595745 (-5575 3925);
PAINT GREEN (-5575 3925);
DISPLAY INVISIBLE (-5575 3925);
FORCEPROP 1 LAST HDL_TAP TRUE
J 0
(-5250 3850);
DISPLAY 1.595745 (-5250 3850);
PAINT GREEN (-5250 3850);
DISPLAY INVISIBLE (-5250 3850);
FORCEPROP 1 LAST PATH I71
J 0
(-5577 3975);
DISPLAY 0.872340 (-5577 3975);
PAINT GREEN (-5577 3975);
DISPLAY INVISIBLE (-5577 3975);
FORCEADD OFFPAGE..6
(-6425 4800);
FORCEPROP 2 LAST $XR0 77 
J 0
(-6674 4800);
DISPLAY 0.638298 (-6674 4800);
PAINT MONO (-6674 4800);
FORCEPROP 2 LAST $XR1 78 
J 0
(-6764 4800);
DISPLAY 0.638298 (-6764 4800);
PAINT MONO (-6764 4800);
FORCEPROP 2 LAST CDS_LIB mstr_standard
J 0
(-6425 4800);
PAINT MONO (-6425 4800);
DISPLAY INVISIBLE (-6425 4800);
FORCEPROP 1 LAST OFFPAGE TRUE
J 0
(-6100 4675);
DISPLAY 1.170213 (-6100 4675);
PAINT GREEN (-6100 4675);
DISPLAY INVISIBLE (-6100 4675);
FORCEPROP 1 LAST COMMENT_BODY TRUE
J 0
(-6325 4725);
DISPLAY 1.170213 (-6325 4725);
PAINT GREEN (-6325 4725);
DISPLAY INVISIBLE (-6325 4725);
FORCEPROP 2 LAST PATH I72
J 0
(-6375 4875);
DISPLAY 1.021277 (-6375 4875);
PAINT ORANGE (-6375 4875);
DISPLAY INVISIBLE (-6375 4875);
FORCEADD TAP..6
(-5575 4025);
FORCEPROP 3 LASTPIN (-5525 4025) SIG_NAME M_G_DQ<50>
J 0
(-5515 4035);
DISPLAY 0.659574 (-5515 4035);
PAINT MONO (-5515 4035);
DISPLAY INVISIBLE (-5515 4035);
FORCEPROP 1 LASTPIN (-5525 4025) BN 50
J 0
(-5577 4033);
DISPLAY 0.617021 (-5577 4033);
PAINT GREEN (-5577 4033);
FORCEPROP 2 LAST CDS_LIB mstr_standard
J 0
(-5575 4025);
PAINT MONO (-5575 4025);
DISPLAY INVISIBLE (-5575 4025);
FORCEPROP 1 LAST BODY_TYPE PLUMBING
J 0
(-5575 3975);
DISPLAY 1.595745 (-5575 3975);
PAINT GREEN (-5575 3975);
DISPLAY INVISIBLE (-5575 3975);
FORCEPROP 1 LAST HDL_TAP TRUE
J 0
(-5250 3900);
DISPLAY 1.595745 (-5250 3900);
PAINT GREEN (-5250 3900);
DISPLAY INVISIBLE (-5250 3900);
FORCEPROP 1 LAST PATH I73
J 0
(-5577 4025);
DISPLAY 0.872340 (-5577 4025);
PAINT GREEN (-5577 4025);
DISPLAY INVISIBLE (-5577 4025);
FORCEADD TAP..6
(-5575 4075);
FORCEPROP 3 LASTPIN (-5525 4075) SIG_NAME M_G_DQ<51>
J 0
(-5515 4085);
DISPLAY 0.659574 (-5515 4085);
PAINT MONO (-5515 4085);
DISPLAY INVISIBLE (-5515 4085);
FORCEPROP 1 LASTPIN (-5525 4075) BN 51
J 0
(-5577 4083);
DISPLAY 0.617021 (-5577 4083);
PAINT GREEN (-5577 4083);
FORCEPROP 2 LAST CDS_LIB mstr_standard
J 0
(-5575 4075);
PAINT MONO (-5575 4075);
DISPLAY INVISIBLE (-5575 4075);
FORCEPROP 1 LAST BODY_TYPE PLUMBING
J 0
(-5575 4025);
DISPLAY 1.595745 (-5575 4025);
PAINT GREEN (-5575 4025);
DISPLAY INVISIBLE (-5575 4025);
FORCEPROP 1 LAST HDL_TAP TRUE
J 0
(-5250 3950);
DISPLAY 1.595745 (-5250 3950);
PAINT GREEN (-5250 3950);
DISPLAY INVISIBLE (-5250 3950);
FORCEPROP 1 LAST PATH I74
J 0
(-5577 4075);
DISPLAY 0.872340 (-5577 4075);
PAINT GREEN (-5577 4075);
DISPLAY INVISIBLE (-5577 4075);
FORCEADD TAP..6
(-5575 4125);
FORCEPROP 3 LASTPIN (-5525 4125) SIG_NAME M_G_DQ<52>
J 0
(-5515 4135);
DISPLAY 0.659574 (-5515 4135);
PAINT MONO (-5515 4135);
DISPLAY INVISIBLE (-5515 4135);
FORCEPROP 1 LASTPIN (-5525 4125) BN 52
J 0
(-5577 4133);
DISPLAY 0.617021 (-5577 4133);
PAINT GREEN (-5577 4133);
FORCEPROP 2 LAST CDS_LIB mstr_standard
J 0
(-5575 4125);
PAINT MONO (-5575 4125);
DISPLAY INVISIBLE (-5575 4125);
FORCEPROP 1 LAST BODY_TYPE PLUMBING
J 0
(-5575 4075);
DISPLAY 1.595745 (-5575 4075);
PAINT GREEN (-5575 4075);
DISPLAY INVISIBLE (-5575 4075);
FORCEPROP 1 LAST HDL_TAP TRUE
J 0
(-5250 4000);
DISPLAY 1.595745 (-5250 4000);
PAINT GREEN (-5250 4000);
DISPLAY INVISIBLE (-5250 4000);
FORCEPROP 1 LAST PATH I75
J 0
(-5577 4125);
DISPLAY 0.872340 (-5577 4125);
PAINT GREEN (-5577 4125);
DISPLAY INVISIBLE (-5577 4125);
FORCEADD TAP..6
(-5575 4175);
FORCEPROP 3 LASTPIN (-5525 4175) SIG_NAME M_G_DQ<53>
J 0
(-5515 4185);
DISPLAY 0.659574 (-5515 4185);
PAINT MONO (-5515 4185);
DISPLAY INVISIBLE (-5515 4185);
FORCEPROP 1 LASTPIN (-5525 4175) BN 53
J 0
(-5577 4183);
DISPLAY 0.617021 (-5577 4183);
PAINT GREEN (-5577 4183);
FORCEPROP 2 LAST CDS_LIB mstr_standard
J 0
(-5575 4175);
PAINT MONO (-5575 4175);
DISPLAY INVISIBLE (-5575 4175);
FORCEPROP 1 LAST BODY_TYPE PLUMBING
J 0
(-5575 4125);
DISPLAY 1.595745 (-5575 4125);
PAINT GREEN (-5575 4125);
DISPLAY INVISIBLE (-5575 4125);
FORCEPROP 1 LAST HDL_TAP TRUE
J 0
(-5250 4050);
DISPLAY 1.595745 (-5250 4050);
PAINT GREEN (-5250 4050);
DISPLAY INVISIBLE (-5250 4050);
FORCEPROP 1 LAST PATH I76
J 0
(-5577 4175);
DISPLAY 0.872340 (-5577 4175);
PAINT GREEN (-5577 4175);
DISPLAY INVISIBLE (-5577 4175);
FORCEADD TAP..6
(-5575 4225);
FORCEPROP 3 LASTPIN (-5525 4225) SIG_NAME M_G_DQ<54>
J 0
(-5515 4235);
DISPLAY 0.659574 (-5515 4235);
PAINT MONO (-5515 4235);
DISPLAY INVISIBLE (-5515 4235);
FORCEPROP 1 LASTPIN (-5525 4225) BN 54
J 0
(-5577 4233);
DISPLAY 0.617021 (-5577 4233);
PAINT GREEN (-5577 4233);
FORCEPROP 2 LAST CDS_LIB mstr_standard
J 0
(-5575 4225);
PAINT MONO (-5575 4225);
DISPLAY INVISIBLE (-5575 4225);
FORCEPROP 1 LAST BODY_TYPE PLUMBING
J 0
(-5575 4175);
DISPLAY 1.595745 (-5575 4175);
PAINT GREEN (-5575 4175);
DISPLAY INVISIBLE (-5575 4175);
FORCEPROP 1 LAST HDL_TAP TRUE
J 0
(-5250 4100);
DISPLAY 1.595745 (-5250 4100);
PAINT GREEN (-5250 4100);
DISPLAY INVISIBLE (-5250 4100);
FORCEPROP 1 LAST PATH I77
J 0
(-5577 4225);
DISPLAY 0.872340 (-5577 4225);
PAINT GREEN (-5577 4225);
DISPLAY INVISIBLE (-5577 4225);
FORCEADD TAP..6
(-5575 4275);
FORCEPROP 3 LASTPIN (-5525 4275) SIG_NAME M_G_DQ<55>
J 0
(-5515 4285);
DISPLAY 0.659574 (-5515 4285);
PAINT MONO (-5515 4285);
DISPLAY INVISIBLE (-5515 4285);
FORCEPROP 1 LASTPIN (-5525 4275) BN 55
J 0
(-5577 4283);
DISPLAY 0.617021 (-5577 4283);
PAINT GREEN (-5577 4283);
FORCEPROP 2 LAST CDS_LIB mstr_standard
J 0
(-5575 4275);
PAINT MONO (-5575 4275);
DISPLAY INVISIBLE (-5575 4275);
FORCEPROP 1 LAST BODY_TYPE PLUMBING
J 0
(-5575 4225);
DISPLAY 1.595745 (-5575 4225);
PAINT GREEN (-5575 4225);
DISPLAY INVISIBLE (-5575 4225);
FORCEPROP 1 LAST HDL_TAP TRUE
J 0
(-5250 4150);
DISPLAY 1.595745 (-5250 4150);
PAINT GREEN (-5250 4150);
DISPLAY INVISIBLE (-5250 4150);
FORCEPROP 1 LAST PATH I78
J 0
(-5577 4275);
DISPLAY 0.872340 (-5577 4275);
PAINT GREEN (-5577 4275);
DISPLAY INVISIBLE (-5577 4275);
FORCEADD TAP..6
(-5575 4325);
FORCEPROP 3 LASTPIN (-5525 4325) SIG_NAME M_G_DQ<56>
J 0
(-5515 4335);
DISPLAY 0.659574 (-5515 4335);
PAINT MONO (-5515 4335);
DISPLAY INVISIBLE (-5515 4335);
FORCEPROP 1 LASTPIN (-5525 4325) BN 56
J 0
(-5577 4333);
DISPLAY 0.617021 (-5577 4333);
PAINT GREEN (-5577 4333);
FORCEPROP 2 LAST CDS_LIB mstr_standard
J 0
(-5575 4325);
PAINT MONO (-5575 4325);
DISPLAY INVISIBLE (-5575 4325);
FORCEPROP 1 LAST BODY_TYPE PLUMBING
J 0
(-5575 4275);
DISPLAY 1.595745 (-5575 4275);
PAINT GREEN (-5575 4275);
DISPLAY INVISIBLE (-5575 4275);
FORCEPROP 1 LAST HDL_TAP TRUE
J 0
(-5250 4200);
DISPLAY 1.595745 (-5250 4200);
PAINT GREEN (-5250 4200);
DISPLAY INVISIBLE (-5250 4200);
FORCEPROP 1 LAST PATH I79
J 0
(-5577 4325);
DISPLAY 0.872340 (-5577 4325);
PAINT GREEN (-5577 4325);
DISPLAY INVISIBLE (-5577 4325);
FORCEADD TAP..6
(-5575 725);
FORCEPROP 3 LASTPIN (-5525 725) SIG_NAME M_G_CLK_DN<2>
J 0
(-5515 735);
DISPLAY 0.659574 (-5515 735);
PAINT MONO (-5515 735);
DISPLAY INVISIBLE (-5515 735);
FORCEPROP 1 LASTPIN (-5525 725) BN 2
J 0
(-5577 733);
DISPLAY 0.617021 (-5577 733);
PAINT GREEN (-5577 733);
FORCEPROP 2 LAST CDS_LIB mstr_standard
J 0
(-5575 725);
PAINT MONO (-5575 725);
DISPLAY INVISIBLE (-5575 725);
FORCEPROP 1 LAST BODY_TYPE PLUMBING
J 0
(-5575 675);
DISPLAY 1.595745 (-5575 675);
PAINT GREEN (-5575 675);
DISPLAY INVISIBLE (-5575 675);
FORCEPROP 1 LAST HDL_TAP TRUE
J 0
(-5250 600);
DISPLAY 1.595745 (-5250 600);
PAINT GREEN (-5250 600);
DISPLAY INVISIBLE (-5250 600);
FORCEPROP 1 LAST PATH I8
J 0
(-5577 725);
DISPLAY 0.872340 (-5577 725);
PAINT GREEN (-5577 725);
DISPLAY INVISIBLE (-5577 725);
FORCEADD TAP..6
(-5575 4375);
FORCEPROP 3 LASTPIN (-5525 4375) SIG_NAME M_G_DQ<57>
J 0
(-5515 4385);
DISPLAY 0.659574 (-5515 4385);
PAINT MONO (-5515 4385);
DISPLAY INVISIBLE (-5515 4385);
FORCEPROP 1 LASTPIN (-5525 4375) BN 57
J 0
(-5577 4383);
DISPLAY 0.617021 (-5577 4383);
PAINT GREEN (-5577 4383);
FORCEPROP 2 LAST CDS_LIB mstr_standard
J 0
(-5575 4375);
PAINT MONO (-5575 4375);
DISPLAY INVISIBLE (-5575 4375);
FORCEPROP 1 LAST BODY_TYPE PLUMBING
J 0
(-5575 4325);
DISPLAY 1.595745 (-5575 4325);
PAINT GREEN (-5575 4325);
DISPLAY INVISIBLE (-5575 4325);
FORCEPROP 1 LAST HDL_TAP TRUE
J 0
(-5250 4250);
DISPLAY 1.595745 (-5250 4250);
PAINT GREEN (-5250 4250);
DISPLAY INVISIBLE (-5250 4250);
FORCEPROP 1 LAST PATH I80
J 0
(-5577 4375);
DISPLAY 0.872340 (-5577 4375);
PAINT GREEN (-5577 4375);
DISPLAY INVISIBLE (-5577 4375);
FORCEADD TAP..6
(-5575 4425);
FORCEPROP 3 LASTPIN (-5525 4425) SIG_NAME M_G_DQ<58>
J 0
(-5515 4435);
DISPLAY 0.659574 (-5515 4435);
PAINT MONO (-5515 4435);
DISPLAY INVISIBLE (-5515 4435);
FORCEPROP 1 LASTPIN (-5525 4425) BN 58
J 0
(-5577 4433);
DISPLAY 0.617021 (-5577 4433);
PAINT GREEN (-5577 4433);
FORCEPROP 2 LAST CDS_LIB mstr_standard
J 0
(-5575 4425);
PAINT MONO (-5575 4425);
DISPLAY INVISIBLE (-5575 4425);
FORCEPROP 1 LAST BODY_TYPE PLUMBING
J 0
(-5575 4375);
DISPLAY 1.595745 (-5575 4375);
PAINT GREEN (-5575 4375);
DISPLAY INVISIBLE (-5575 4375);
FORCEPROP 1 LAST HDL_TAP TRUE
J 0
(-5250 4300);
DISPLAY 1.595745 (-5250 4300);
PAINT GREEN (-5250 4300);
DISPLAY INVISIBLE (-5250 4300);
FORCEPROP 1 LAST PATH I81
J 0
(-5577 4425);
DISPLAY 0.872340 (-5577 4425);
PAINT GREEN (-5577 4425);
DISPLAY INVISIBLE (-5577 4425);
FORCEADD TAP..6
(-5575 4475);
FORCEPROP 3 LASTPIN (-5525 4475) SIG_NAME M_G_DQ<59>
J 0
(-5515 4485);
DISPLAY 0.659574 (-5515 4485);
PAINT MONO (-5515 4485);
DISPLAY INVISIBLE (-5515 4485);
FORCEPROP 1 LASTPIN (-5525 4475) BN 59
J 0
(-5577 4483);
DISPLAY 0.617021 (-5577 4483);
PAINT GREEN (-5577 4483);
FORCEPROP 2 LAST CDS_LIB mstr_standard
J 0
(-5575 4475);
PAINT MONO (-5575 4475);
DISPLAY INVISIBLE (-5575 4475);
FORCEPROP 1 LAST BODY_TYPE PLUMBING
J 0
(-5575 4425);
DISPLAY 1.595745 (-5575 4425);
PAINT GREEN (-5575 4425);
DISPLAY INVISIBLE (-5575 4425);
FORCEPROP 1 LAST HDL_TAP TRUE
J 0
(-5250 4350);
DISPLAY 1.595745 (-5250 4350);
PAINT GREEN (-5250 4350);
DISPLAY INVISIBLE (-5250 4350);
FORCEPROP 1 LAST PATH I82
J 0
(-5577 4475);
DISPLAY 0.872340 (-5577 4475);
PAINT GREEN (-5577 4475);
DISPLAY INVISIBLE (-5577 4475);
FORCEADD TAP..6
(-5575 4525);
FORCEPROP 3 LASTPIN (-5525 4525) SIG_NAME M_G_DQ<60>
J 0
(-5515 4535);
DISPLAY 0.659574 (-5515 4535);
PAINT MONO (-5515 4535);
DISPLAY INVISIBLE (-5515 4535);
FORCEPROP 1 LASTPIN (-5525 4525) BN 60
J 0
(-5577 4533);
DISPLAY 0.617021 (-5577 4533);
PAINT GREEN (-5577 4533);
FORCEPROP 2 LAST CDS_LIB mstr_standard
J 0
(-5575 4525);
PAINT MONO (-5575 4525);
DISPLAY INVISIBLE (-5575 4525);
FORCEPROP 1 LAST BODY_TYPE PLUMBING
J 0
(-5575 4475);
DISPLAY 1.595745 (-5575 4475);
PAINT GREEN (-5575 4475);
DISPLAY INVISIBLE (-5575 4475);
FORCEPROP 1 LAST HDL_TAP TRUE
J 0
(-5250 4400);
DISPLAY 1.595745 (-5250 4400);
PAINT GREEN (-5250 4400);
DISPLAY INVISIBLE (-5250 4400);
FORCEPROP 1 LAST PATH I83
J 0
(-5577 4525);
DISPLAY 0.872340 (-5577 4525);
PAINT GREEN (-5577 4525);
DISPLAY INVISIBLE (-5577 4525);
FORCEADD TAP..6
(-5575 4575);
FORCEPROP 3 LASTPIN (-5525 4575) SIG_NAME M_G_DQ<61>
J 0
(-5515 4585);
DISPLAY 0.659574 (-5515 4585);
PAINT MONO (-5515 4585);
DISPLAY INVISIBLE (-5515 4585);
FORCEPROP 1 LASTPIN (-5525 4575) BN 61
J 0
(-5577 4583);
DISPLAY 0.617021 (-5577 4583);
PAINT GREEN (-5577 4583);
FORCEPROP 2 LAST CDS_LIB mstr_standard
J 0
(-5575 4575);
PAINT MONO (-5575 4575);
DISPLAY INVISIBLE (-5575 4575);
FORCEPROP 1 LAST BODY_TYPE PLUMBING
J 0
(-5575 4525);
DISPLAY 1.595745 (-5575 4525);
PAINT GREEN (-5575 4525);
DISPLAY INVISIBLE (-5575 4525);
FORCEPROP 1 LAST HDL_TAP TRUE
J 0
(-5250 4450);
DISPLAY 1.595745 (-5250 4450);
PAINT GREEN (-5250 4450);
DISPLAY INVISIBLE (-5250 4450);
FORCEPROP 1 LAST PATH I84
J 0
(-5577 4575);
DISPLAY 0.872340 (-5577 4575);
PAINT GREEN (-5577 4575);
DISPLAY INVISIBLE (-5577 4575);
FORCEADD TAP..6
(-5575 4625);
FORCEPROP 3 LASTPIN (-5525 4625) SIG_NAME M_G_DQ<62>
J 0
(-5515 4635);
DISPLAY 0.659574 (-5515 4635);
PAINT MONO (-5515 4635);
DISPLAY INVISIBLE (-5515 4635);
FORCEPROP 1 LASTPIN (-5525 4625) BN 62
J 0
(-5577 4633);
DISPLAY 0.617021 (-5577 4633);
PAINT GREEN (-5577 4633);
FORCEPROP 2 LAST CDS_LIB mstr_standard
J 0
(-5575 4625);
PAINT MONO (-5575 4625);
DISPLAY INVISIBLE (-5575 4625);
FORCEPROP 1 LAST BODY_TYPE PLUMBING
J 0
(-5575 4575);
DISPLAY 1.595745 (-5575 4575);
PAINT GREEN (-5575 4575);
DISPLAY INVISIBLE (-5575 4575);
FORCEPROP 1 LAST HDL_TAP TRUE
J 0
(-5250 4500);
DISPLAY 1.595745 (-5250 4500);
PAINT GREEN (-5250 4500);
DISPLAY INVISIBLE (-5250 4500);
FORCEPROP 1 LAST PATH I85
J 0
(-5577 4625);
DISPLAY 0.872340 (-5577 4625);
PAINT GREEN (-5577 4625);
DISPLAY INVISIBLE (-5577 4625);
FORCEADD TAP..6
(-5575 4675);
FORCEPROP 3 LASTPIN (-5525 4675) SIG_NAME M_G_DQ<63>
J 0
(-5515 4685);
DISPLAY 0.659574 (-5515 4685);
PAINT MONO (-5515 4685);
DISPLAY INVISIBLE (-5515 4685);
FORCEPROP 1 LASTPIN (-5525 4675) BN 63
J 0
(-5577 4683);
DISPLAY 0.617021 (-5577 4683);
PAINT GREEN (-5577 4683);
FORCEPROP 2 LAST CDS_LIB mstr_standard
J 0
(-5575 4675);
PAINT MONO (-5575 4675);
DISPLAY INVISIBLE (-5575 4675);
FORCEPROP 1 LAST BODY_TYPE PLUMBING
J 0
(-5575 4625);
DISPLAY 1.595745 (-5575 4625);
PAINT GREEN (-5575 4625);
DISPLAY INVISIBLE (-5575 4625);
FORCEPROP 1 LAST HDL_TAP TRUE
J 0
(-5250 4550);
DISPLAY 1.595745 (-5250 4550);
PAINT GREEN (-5250 4550);
DISPLAY INVISIBLE (-5250 4550);
FORCEPROP 1 LAST PATH I86
J 0
(-5577 4675);
DISPLAY 0.872340 (-5577 4675);
PAINT GREEN (-5577 4675);
DISPLAY INVISIBLE (-5577 4675);
FORCEADD TAP..6
R 2
(-2850 775);
FORCEPROP 3 LASTPIN (-2900 775) SIG_NAME M_G_BA<1>
J 0
(-2890 785);
DISPLAY 0.659574 (-2890 785);
PAINT MONO (-2890 785);
DISPLAY INVISIBLE (-2890 785);
FORCEPROP 1 LASTPIN (-2900 775) BN 1
J 2
(-2848 783);
DISPLAY 0.617021 (-2848 783);
PAINT GREEN (-2848 783);
FORCEPROP 2 LAST CDS_LIB mstr_standard
J 0
(-2850 775);
PAINT MONO (-2850 775);
DISPLAY INVISIBLE (-2850 775);
FORCEPROP 1 LAST BODY_TYPE PLUMBING
J 2
(-2850 725);
DISPLAY 1.595745 (-2850 725);
PAINT GREEN (-2850 725);
DISPLAY INVISIBLE (-2850 725);
FORCEPROP 1 LAST HDL_TAP TRUE
J 2
(-3175 650);
DISPLAY 1.595745 (-3175 650);
PAINT GREEN (-3175 650);
DISPLAY INVISIBLE (-3175 650);
FORCEPROP 1 LAST PATH I87
J 2
(-2848 775);
DISPLAY 0.872340 (-2848 775);
PAINT GREEN (-2848 775);
DISPLAY INVISIBLE (-2848 775);
FORCEADD TAP..6
R 2
(-2850 725);
FORCEPROP 3 LASTPIN (-2900 725) SIG_NAME M_G_BA<0>
J 0
(-2890 735);
DISPLAY 0.659574 (-2890 735);
PAINT MONO (-2890 735);
DISPLAY INVISIBLE (-2890 735);
FORCEPROP 1 LASTPIN (-2900 725) BN 0
J 2
(-2848 733);
DISPLAY 0.617021 (-2848 733);
PAINT GREEN (-2848 733);
FORCEPROP 2 LAST CDS_LIB mstr_standard
J 0
(-2850 725);
PAINT MONO (-2850 725);
DISPLAY INVISIBLE (-2850 725);
FORCEPROP 1 LAST BODY_TYPE PLUMBING
J 2
(-2850 675);
DISPLAY 1.595745 (-2850 675);
PAINT GREEN (-2850 675);
DISPLAY INVISIBLE (-2850 675);
FORCEPROP 1 LAST HDL_TAP TRUE
J 2
(-3175 600);
DISPLAY 1.595745 (-3175 600);
PAINT GREEN (-3175 600);
DISPLAY INVISIBLE (-3175 600);
FORCEPROP 1 LAST PATH I88
J 2
(-2848 725);
DISPLAY 0.872340 (-2848 725);
PAINT GREEN (-2848 725);
DISPLAY INVISIBLE (-2848 725);
FORCEADD TAP..6
R 2
(-2850 825);
FORCEPROP 3 LASTPIN (-2900 825) SIG_NAME M_G_BG<0>
J 0
(-2890 835);
DISPLAY 0.659574 (-2890 835);
PAINT MONO (-2890 835);
DISPLAY INVISIBLE (-2890 835);
FORCEPROP 1 LASTPIN (-2900 825) BN 0
J 2
(-2848 833);
DISPLAY 0.617021 (-2848 833);
PAINT GREEN (-2848 833);
FORCEPROP 2 LAST CDS_LIB mstr_standard
J 0
(-2850 825);
PAINT MONO (-2850 825);
DISPLAY INVISIBLE (-2850 825);
FORCEPROP 1 LAST BODY_TYPE PLUMBING
J 2
(-2850 775);
DISPLAY 1.595745 (-2850 775);
PAINT GREEN (-2850 775);
DISPLAY INVISIBLE (-2850 775);
FORCEPROP 1 LAST HDL_TAP TRUE
J 2
(-3175 700);
DISPLAY 1.595745 (-3175 700);
PAINT GREEN (-3175 700);
DISPLAY INVISIBLE (-3175 700);
FORCEPROP 1 LAST PATH I89
J 2
(-2848 825);
DISPLAY 0.872340 (-2848 825);
PAINT GREEN (-2848 825);
DISPLAY INVISIBLE (-2848 825);
FORCEADD TAP..6
(-5575 875);
FORCEPROP 3 LASTPIN (-5525 875) SIG_NAME M_G_CLK_DP<1>
J 0
(-5515 885);
DISPLAY 0.659574 (-5515 885);
PAINT MONO (-5515 885);
DISPLAY INVISIBLE (-5515 885);
FORCEPROP 1 LASTPIN (-5525 875) BN 1
J 0
(-5577 883);
DISPLAY 0.617021 (-5577 883);
PAINT GREEN (-5577 883);
FORCEPROP 2 LAST CDS_LIB mstr_standard
J 0
(-5575 875);
PAINT MONO (-5575 875);
DISPLAY INVISIBLE (-5575 875);
FORCEPROP 1 LAST BODY_TYPE PLUMBING
J 0
(-5575 825);
DISPLAY 1.595745 (-5575 825);
PAINT GREEN (-5575 825);
DISPLAY INVISIBLE (-5575 825);
FORCEPROP 1 LAST HDL_TAP TRUE
J 0
(-5250 750);
DISPLAY 1.595745 (-5250 750);
PAINT GREEN (-5250 750);
DISPLAY INVISIBLE (-5250 750);
FORCEPROP 1 LAST PATH I9
J 0
(-5577 875);
DISPLAY 0.872340 (-5577 875);
PAINT GREEN (-5577 875);
DISPLAY INVISIBLE (-5577 875);
FORCEADD TAP..6
R 2
(-2850 875);
FORCEPROP 3 LASTPIN (-2900 875) SIG_NAME M_G_BG<1>
J 0
(-2890 885);
DISPLAY 0.659574 (-2890 885);
PAINT MONO (-2890 885);
DISPLAY INVISIBLE (-2890 885);
FORCEPROP 1 LASTPIN (-2900 875) BN 1
J 2
(-2848 883);
DISPLAY 0.617021 (-2848 883);
PAINT GREEN (-2848 883);
FORCEPROP 2 LAST CDS_LIB mstr_standard
J 0
(-2850 875);
PAINT MONO (-2850 875);
DISPLAY INVISIBLE (-2850 875);
FORCEPROP 1 LAST BODY_TYPE PLUMBING
J 2
(-2850 825);
DISPLAY 1.595745 (-2850 825);
PAINT GREEN (-2850 825);
DISPLAY INVISIBLE (-2850 825);
FORCEPROP 1 LAST HDL_TAP TRUE
J 2
(-3175 750);
DISPLAY 1.595745 (-3175 750);
PAINT GREEN (-3175 750);
DISPLAY INVISIBLE (-3175 750);
FORCEPROP 1 LAST PATH I90
J 2
(-2848 875);
DISPLAY 0.872340 (-2848 875);
PAINT GREEN (-2848 875);
DISPLAY INVISIBLE (-2848 875);
FORCEADD TAP..6
R 2
(-2850 1075);
FORCEPROP 3 LASTPIN (-2900 1075) SIG_NAME M_G_CS_N<2>
J 0
(-2890 1085);
DISPLAY 0.659574 (-2890 1085);
PAINT MONO (-2890 1085);
DISPLAY INVISIBLE (-2890 1085);
FORCEPROP 1 LASTPIN (-2900 1075) BN 2
J 2
(-2848 1083);
DISPLAY 0.617021 (-2848 1083);
PAINT GREEN (-2848 1083);
FORCEPROP 2 LAST CDS_LIB mstr_standard
J 0
(-2850 1075);
PAINT MONO (-2850 1075);
DISPLAY INVISIBLE (-2850 1075);
FORCEPROP 1 LAST BODY_TYPE PLUMBING
J 2
(-2850 1025);
DISPLAY 1.595745 (-2850 1025);
PAINT GREEN (-2850 1025);
DISPLAY INVISIBLE (-2850 1025);
FORCEPROP 1 LAST HDL_TAP TRUE
J 2
(-3175 950);
DISPLAY 1.595745 (-3175 950);
PAINT GREEN (-3175 950);
DISPLAY INVISIBLE (-3175 950);
FORCEPROP 1 LAST PATH I91
J 2
(-2848 1075);
DISPLAY 0.872340 (-2848 1075);
PAINT GREEN (-2848 1075);
DISPLAY INVISIBLE (-2848 1075);
FORCEADD TAP..6
R 2
(-2850 1025);
FORCEPROP 3 LASTPIN (-2900 1025) SIG_NAME M_G_CS_N<1>
J 0
(-2890 1035);
DISPLAY 0.659574 (-2890 1035);
PAINT MONO (-2890 1035);
DISPLAY INVISIBLE (-2890 1035);
FORCEPROP 1 LASTPIN (-2900 1025) BN 1
J 2
(-2848 1033);
DISPLAY 0.617021 (-2848 1033);
PAINT GREEN (-2848 1033);
FORCEPROP 2 LAST CDS_LIB mstr_standard
J 0
(-2850 1025);
PAINT MONO (-2850 1025);
DISPLAY INVISIBLE (-2850 1025);
FORCEPROP 1 LAST BODY_TYPE PLUMBING
J 2
(-2850 975);
DISPLAY 1.595745 (-2850 975);
PAINT GREEN (-2850 975);
DISPLAY INVISIBLE (-2850 975);
FORCEPROP 1 LAST HDL_TAP TRUE
J 2
(-3175 900);
DISPLAY 1.595745 (-3175 900);
PAINT GREEN (-3175 900);
DISPLAY INVISIBLE (-3175 900);
FORCEPROP 1 LAST PATH I92
J 2
(-2848 1025);
DISPLAY 0.872340 (-2848 1025);
PAINT GREEN (-2848 1025);
DISPLAY INVISIBLE (-2848 1025);
FORCEADD TAP..6
R 2
(-2850 975);
FORCEPROP 3 LASTPIN (-2900 975) SIG_NAME M_G_CS_N<0>
J 0
(-2890 985);
DISPLAY 0.659574 (-2890 985);
PAINT MONO (-2890 985);
DISPLAY INVISIBLE (-2890 985);
FORCEPROP 1 LASTPIN (-2900 975) BN 0
J 2
(-2848 983);
DISPLAY 0.617021 (-2848 983);
PAINT GREEN (-2848 983);
FORCEPROP 2 LAST CDS_LIB mstr_standard
J 0
(-2850 975);
PAINT MONO (-2850 975);
DISPLAY INVISIBLE (-2850 975);
FORCEPROP 1 LAST BODY_TYPE PLUMBING
J 2
(-2850 925);
DISPLAY 1.595745 (-2850 925);
PAINT GREEN (-2850 925);
DISPLAY INVISIBLE (-2850 925);
FORCEPROP 1 LAST HDL_TAP TRUE
J 2
(-3175 850);
DISPLAY 1.595745 (-3175 850);
PAINT GREEN (-3175 850);
DISPLAY INVISIBLE (-3175 850);
FORCEPROP 1 LAST PATH I93
J 2
(-2848 975);
DISPLAY 0.872340 (-2848 975);
PAINT GREEN (-2848 975);
DISPLAY INVISIBLE (-2848 975);
FORCEADD TAP..6
R 2
(-2850 1175);
FORCEPROP 3 LASTPIN (-2900 1175) SIG_NAME M_G_CS_N<4>
J 0
(-2890 1185);
DISPLAY 0.659574 (-2890 1185);
PAINT MONO (-2890 1185);
DISPLAY INVISIBLE (-2890 1185);
FORCEPROP 1 LASTPIN (-2900 1175) BN 4
J 2
(-2848 1183);
DISPLAY 0.617021 (-2848 1183);
PAINT GREEN (-2848 1183);
FORCEPROP 2 LAST CDS_LIB mstr_standard
J 0
(-2850 1175);
PAINT MONO (-2850 1175);
DISPLAY INVISIBLE (-2850 1175);
FORCEPROP 1 LAST BODY_TYPE PLUMBING
J 2
(-2850 1125);
DISPLAY 1.595745 (-2850 1125);
PAINT GREEN (-2850 1125);
DISPLAY INVISIBLE (-2850 1125);
FORCEPROP 1 LAST HDL_TAP TRUE
J 2
(-3175 1050);
DISPLAY 1.595745 (-3175 1050);
PAINT GREEN (-3175 1050);
DISPLAY INVISIBLE (-3175 1050);
FORCEPROP 1 LAST PATH I94
J 2
(-2848 1175);
DISPLAY 0.872340 (-2848 1175);
PAINT GREEN (-2848 1175);
DISPLAY INVISIBLE (-2848 1175);
FORCEADD TAP..6
R 2
(-2850 1125);
FORCEPROP 3 LASTPIN (-2900 1125) SIG_NAME M_G_CS_N<3>
J 0
(-2890 1135);
DISPLAY 0.659574 (-2890 1135);
PAINT MONO (-2890 1135);
DISPLAY INVISIBLE (-2890 1135);
FORCEPROP 1 LASTPIN (-2900 1125) BN 3
J 2
(-2848 1133);
DISPLAY 0.617021 (-2848 1133);
PAINT GREEN (-2848 1133);
FORCEPROP 2 LAST CDS_LIB mstr_standard
J 0
(-2850 1125);
PAINT MONO (-2850 1125);
DISPLAY INVISIBLE (-2850 1125);
FORCEPROP 1 LAST BODY_TYPE PLUMBING
J 2
(-2850 1075);
DISPLAY 1.595745 (-2850 1075);
PAINT GREEN (-2850 1075);
DISPLAY INVISIBLE (-2850 1075);
FORCEPROP 1 LAST HDL_TAP TRUE
J 2
(-3175 1000);
DISPLAY 1.595745 (-3175 1000);
PAINT GREEN (-3175 1000);
DISPLAY INVISIBLE (-3175 1000);
FORCEPROP 1 LAST PATH I95
J 2
(-2848 1125);
DISPLAY 0.872340 (-2848 1125);
PAINT GREEN (-2848 1125);
DISPLAY INVISIBLE (-2848 1125);
FORCEADD TAP..6
R 2
(-2850 1225);
FORCEPROP 3 LASTPIN (-2900 1225) SIG_NAME M_G_CS_N<5>
J 0
(-2890 1235);
DISPLAY 0.659574 (-2890 1235);
PAINT MONO (-2890 1235);
DISPLAY INVISIBLE (-2890 1235);
FORCEPROP 1 LASTPIN (-2900 1225) BN 5
J 2
(-2848 1233);
DISPLAY 0.617021 (-2848 1233);
PAINT GREEN (-2848 1233);
FORCEPROP 2 LAST CDS_LIB mstr_standard
J 0
(-2850 1225);
PAINT MONO (-2850 1225);
DISPLAY INVISIBLE (-2850 1225);
FORCEPROP 1 LAST BODY_TYPE PLUMBING
J 2
(-2850 1175);
DISPLAY 1.595745 (-2850 1175);
PAINT GREEN (-2850 1175);
DISPLAY INVISIBLE (-2850 1175);
FORCEPROP 1 LAST HDL_TAP TRUE
J 2
(-3175 1100);
DISPLAY 1.595745 (-3175 1100);
PAINT GREEN (-3175 1100);
DISPLAY INVISIBLE (-3175 1100);
FORCEPROP 1 LAST PATH I96
J 2
(-2848 1225);
DISPLAY 0.872340 (-2848 1225);
PAINT GREEN (-2848 1225);
DISPLAY INVISIBLE (-2848 1225);
FORCEADD TAP..6
R 2
(-2850 1275);
FORCEPROP 3 LASTPIN (-2900 1275) SIG_NAME M_G_CS_N<6>
J 0
(-2890 1285);
DISPLAY 0.659574 (-2890 1285);
PAINT MONO (-2890 1285);
DISPLAY INVISIBLE (-2890 1285);
FORCEPROP 1 LASTPIN (-2900 1275) BN 6
J 2
(-2848 1283);
DISPLAY 0.617021 (-2848 1283);
PAINT GREEN (-2848 1283);
FORCEPROP 2 LAST CDS_LIB mstr_standard
J 0
(-2850 1275);
PAINT MONO (-2850 1275);
DISPLAY INVISIBLE (-2850 1275);
FORCEPROP 1 LAST BODY_TYPE PLUMBING
J 2
(-2850 1225);
DISPLAY 1.595745 (-2850 1225);
PAINT GREEN (-2850 1225);
DISPLAY INVISIBLE (-2850 1225);
FORCEPROP 1 LAST HDL_TAP TRUE
J 2
(-3175 1150);
DISPLAY 1.595745 (-3175 1150);
PAINT GREEN (-3175 1150);
DISPLAY INVISIBLE (-3175 1150);
FORCEPROP 1 LAST PATH I97
J 2
(-2848 1275);
DISPLAY 0.872340 (-2848 1275);
PAINT GREEN (-2848 1275);
DISPLAY INVISIBLE (-2848 1275);
FORCEADD TAP..6
R 2
(-2850 1325);
FORCEPROP 3 LASTPIN (-2900 1325) SIG_NAME M_G_CS_N<7>
J 0
(-2890 1335);
DISPLAY 0.659574 (-2890 1335);
PAINT MONO (-2890 1335);
DISPLAY INVISIBLE (-2890 1335);
FORCEPROP 1 LASTPIN (-2900 1325) BN 7
J 2
(-2848 1333);
DISPLAY 0.617021 (-2848 1333);
PAINT GREEN (-2848 1333);
FORCEPROP 2 LAST CDS_LIB mstr_standard
J 0
(-2850 1325);
PAINT MONO (-2850 1325);
DISPLAY INVISIBLE (-2850 1325);
FORCEPROP 1 LAST BODY_TYPE PLUMBING
J 2
(-2850 1275);
DISPLAY 1.595745 (-2850 1275);
PAINT GREEN (-2850 1275);
DISPLAY INVISIBLE (-2850 1275);
FORCEPROP 1 LAST HDL_TAP TRUE
J 2
(-3175 1200);
DISPLAY 1.595745 (-3175 1200);
PAINT GREEN (-3175 1200);
DISPLAY INVISIBLE (-3175 1200);
FORCEPROP 1 LAST PATH I98
J 2
(-2848 1325);
DISPLAY 0.872340 (-2848 1325);
PAINT GREEN (-2848 1325);
DISPLAY INVISIBLE (-2848 1325);
FORCEADD TAP..6
R 2
(-2850 1425);
FORCEPROP 3 LASTPIN (-2900 1425) SIG_NAME M_G_ODT<0>
J 0
(-2890 1435);
DISPLAY 0.659574 (-2890 1435);
PAINT MONO (-2890 1435);
DISPLAY INVISIBLE (-2890 1435);
FORCEPROP 1 LASTPIN (-2900 1425) BN 0
J 2
(-2848 1433);
DISPLAY 0.617021 (-2848 1433);
PAINT GREEN (-2848 1433);
FORCEPROP 2 LAST CDS_LIB mstr_standard
J 0
(-2850 1425);
PAINT MONO (-2850 1425);
DISPLAY INVISIBLE (-2850 1425);
FORCEPROP 1 LAST BODY_TYPE PLUMBING
J 2
(-2850 1375);
DISPLAY 1.595745 (-2850 1375);
PAINT GREEN (-2850 1375);
DISPLAY INVISIBLE (-2850 1375);
FORCEPROP 1 LAST HDL_TAP TRUE
J 2
(-3175 1300);
DISPLAY 1.595745 (-3175 1300);
PAINT GREEN (-3175 1300);
DISPLAY INVISIBLE (-3175 1300);
FORCEPROP 1 LAST PATH I99
J 2
(-2848 1425);
DISPLAY 0.872340 (-2848 1425);
PAINT GREEN (-2848 1425);
DISPLAY INVISIBLE (-2848 1425);
FORCEADD DESIGN_NOTE..1
(-6275 350);
FORCEPROP 0 LAST L1 CPU SYMBOLS 1-30 ARE PRELIMINARY AND SUBJECT TO CHANGE
J 0
(-6475 225);
DISPLAY 1.021277 (-6475 225);
PAINT ORANGE (-6475 225);
FORCEPROP 2 LAST CDS_LIB mstr_symbols
J 0
(-6275 350);
PAINT ORANGE (-6275 350);
DISPLAY INVISIBLE (-6275 350);
FORCEPROP 1 LAST COMMENT_BODY TRUE
J 0
(-6250 450);
DISPLAY 0.978723 (-6250 450);
PAINT ORANGE (-6250 450);
DISPLAY INVISIBLE (-6250 450);
FORCEADD PRELIM..10
(-4215 2565);
PAINT GRAY (-4215 2565);
FORCEPROP 2 LAST CDS_LIB mstr_misc
J 0
(-4215 2565);
PAINT ORANGE (-4215 2565);
DISPLAY INVISIBLE (-4215 2565);
FORCEPROP 1 LAST COMMENT_BODY TRUE
J 0
(-4215 2565);
PAINT ORANGE (-4215 2565);
DISPLAY INVISIBLE (-4215 2565);
FORCEADD INTEL_CORP_BPAGE..1
(0 0);
FORCEPROP 1 LAST CDS_CON_LAST_MODIFIED Tue Dec 01 11:51:33 2015
J 0
(-1425 325);
DISPLAY 1.340426 (-1425 325);
PAINT GREEN (-1425 325);
DISPLAY INVISIBLE (-1425 325);
FORCEPROP 1 LAST CUSTOM_TXT_CDS <CURRENT_DESIGN_SHEET> OF <TOTAL_DESIGN_SHEETS>
J 0
(-500 25);
PAINT GREEN (-500 25);
FORCEPROP 1 LAST CUSTOM_TXT_CDS <CON_LAST_MODIFIED>
J 0
(-1925 350);
PAINT GREEN (-1925 350);
FORCEPROP 2 LAST CUSTOM_TXT_CDS <XR_PAGE_TITLE>
J 0
(-7890 5250);
DISPLAY 0.638298 (-7890 5250);
PAINT PINK (-7890 5250);
DISPLAY INVISIBLE (-7890 5250);
FORCEPROP 1 LAST SCH_ADDRESS3 Santa Clara, CA 95052-8119
J 0
(-3975 25);
DISPLAY 0.617021 (-3975 25);
PAINT GREEN (-3975 25);
FORCEPROP 1 LAST SCH_ADDRESS2 P.O. BOX 58119
J 0
(-3975 75);
DISPLAY 0.617021 (-3975 75);
PAINT GREEN (-3975 75);
FORCEPROP 1 LAST SCH_ADDRESS1 2200 Mission College Blvd.
J 0
(-3975 125);
DISPLAY 0.617021 (-3975 125);
PAINT GREEN (-3975 125);
FORCEPROP 1 LAST SCH_TITLE SKYLAKE - SKT1 - 3 OF 21
J 0
(-7950 50);
DISPLAY 1.212766 (-7950 50);
PAINT GREEN (-7950 50);
FORCEPROP 1 LAST SCH_NUMBER H4694802
J 0
(-1300 150);
DISPLAY 1.212766 (-1300 150);
PAINT YELLOW (-1300 150);
FORCEPROP 1 LAST SCH_DEPT BESD
J 1
(-4450 100);
DISPLAY 1.212766 (-4450 100);
PAINT YELLOW (-4450 100);
FORCEPROP 1 LAST SCH_REV 2.420
J 0
(-250 150);
DISPLAY 0.978723 (-250 150);
PAINT YELLOW (-250 150);
FORCEPROP 2 LAST PAGE_BORDER TRUE
J 0
(-7890 5250);
DISPLAY 0.851064 (-7890 5250);
PAINT PINK (-7890 5250);
DISPLAY INVISIBLE (-7890 5250);
FORCEPROP 2 LAST CDS_LIB mstr_symbols
J 0
(0 0);
PAINT ORANGE (0 0);
DISPLAY INVISIBLE (0 0);
FORCEPROP 1 LAST COMMENT_BODY TRUE
J 0
(12 12);
DISPLAY 0.638298 (12 12);
PAINT GREEN (12 12);
DISPLAY INVISIBLE (12 12);
FORCEPROP 2 LAST CDS_XR_PAGE_TITLE CR-57 : @BASEBOARD_FAB2_LIB.BASEBOARD_FAB2(SCH_1):PAGE57
J 0
(-7890 5250);
DISPLAY 0.638298 (-7890 5250);
PAINT PINK (-7890 5250);
DISPLAY INVISIBLE (-7890 5250);
WIRE 17 -1 (-2800 4700)(-2800 4750);
WIRE 17 -1 (-2800 4650)(-2800 4700);
WIRE 17 -1 (-2050 4750)(-2800 4750);
FORCEPROP 2 LAST SIG_NAME M_G_DQS_DP<17:0>
J 0
(-2700 4760);
DISPLAY 0.617021 (-2700 4760);
PAINT ORANGE (-2700 4760);
WIRE 17 -1 (-2800 4600)(-2800 4650);
WIRE 17 -1 (-2800 4550)(-2800 4600);
WIRE 17 -1 (-2800 4500)(-2800 4550);
WIRE 17 -1 (-2800 4450)(-2800 4500);
WIRE 17 -1 (-2800 4400)(-2800 4450);
WIRE 17 -1 (-2800 4350)(-2800 4400);
WIRE 17 -1 (-2800 4300)(-2800 4350);
WIRE 17 -1 (-2800 4250)(-2800 4300);
WIRE 17 -1 (-2800 4200)(-2800 4250);
WIRE 17 -1 (-2800 4150)(-2800 4200);
WIRE 17 -1 (-2800 4100)(-2800 4150);
WIRE 17 -1 (-2800 4050)(-2800 4100);
WIRE 17 -1 (-2800 4000)(-2800 4050);
WIRE 17 -1 (-2800 3950)(-2800 4000);
WIRE 17 -1 (-2800 3900)(-2800 3950);
WIRE 17 -1 (-2800 3850)(-2800 3900);
WIRE 17 -1 (-2800 3750)(-2800 3775);
WIRE 17 -1 (-2800 3700)(-2800 3750);
WIRE 17 -1 (-2050 3775)(-2800 3775);
FORCEPROP 2 LAST SIG_NAME M_G_DQS_DN<17:0>
J 0
(-2700 3785);
DISPLAY 0.617021 (-2700 3785);
PAINT ORANGE (-2700 3785);
WIRE 17 -1 (-2800 3650)(-2800 3700);
WIRE 17 -1 (-2800 3600)(-2800 3650);
WIRE 17 -1 (-2800 3550)(-2800 3600);
WIRE 17 -1 (-2800 3500)(-2800 3550);
WIRE 17 -1 (-2800 3450)(-2800 3500);
WIRE 17 -1 (-2800 3400)(-2800 3450);
WIRE 17 -1 (-2800 3350)(-2800 3400);
WIRE 17 -1 (-2800 3300)(-2800 3350);
WIRE 17 -1 (-2800 3250)(-2800 3300);
WIRE 17 -1 (-2800 3200)(-2800 3250);
WIRE 17 -1 (-2800 3150)(-2800 3200);
WIRE 17 -1 (-2800 3100)(-2800 3150);
WIRE 17 -1 (-2800 3050)(-2800 3100);
WIRE 17 -1 (-2800 3000)(-2800 3050);
WIRE 17 -1 (-2800 2950)(-2800 3000);
WIRE 17 -1 (-2800 2900)(-2800 2950);
WIRE 17 -1 (-2800 2800)(-2800 2825);
WIRE 17 -1 (-2800 2750)(-2800 2800);
WIRE 17 -1 (-2050 2825)(-2800 2825);
FORCEPROP 2 LAST SIG_NAME M_G_MA<17:0>
J 0
(-2700 2835);
DISPLAY 0.617021 (-2700 2835);
PAINT ORANGE (-2700 2835);
WIRE 17 -1 (-2800 2700)(-2800 2750);
WIRE 17 -1 (-2800 2650)(-2800 2700);
WIRE 17 -1 (-2800 2600)(-2800 2650);
WIRE 17 -1 (-2800 2550)(-2800 2600);
WIRE 17 -1 (-2800 2500)(-2800 2550);
WIRE 17 -1 (-2800 2450)(-2800 2500);
WIRE 17 -1 (-2800 2400)(-2800 2450);
WIRE 17 -1 (-2800 2350)(-2800 2400);
WIRE 17 -1 (-2800 2300)(-2800 2350);
WIRE 17 -1 (-2800 2250)(-2800 2300);
WIRE 17 -1 (-2800 2200)(-2800 2250);
WIRE 17 -1 (-2800 2150)(-2800 2200);
WIRE 17 -1 (-2800 2100)(-2800 2150);
WIRE 17 -1 (-2800 2050)(-2800 2100);
WIRE 17 -1 (-2800 2000)(-2800 2050);
WIRE 17 -1 (-2800 1950)(-2800 2000);
WIRE 17 -1 (-2800 800)(-2800 825);
WIRE 17 -1 (-2800 750)(-2800 800);
WIRE 17 -1 (-2050 825)(-2800 825);
FORCEPROP 2 LAST SIG_NAME M_G_BA<1:0>
J 0
(-2700 835);
DISPLAY 0.617021 (-2700 835);
PAINT ORANGE (-2700 835);
WIRE 17 -1 (-2800 850)(-2800 900);
WIRE 17 -1 (-2800 900)(-2800 925);
WIRE 17 -1 (-2050 925)(-2800 925);
FORCEPROP 2 LAST SIG_NAME M_G_BG<1:0>
J 0
(-2700 935);
DISPLAY 0.617021 (-2700 935);
PAINT ORANGE (-2700 935);
WIRE 17 -1 (-2800 1850)(-2800 1875);
WIRE 17 -1 (-2800 1800)(-2800 1850);
WIRE 17 -1 (-2050 1875)(-2800 1875);
FORCEPROP 2 LAST SIG_NAME M_G_CKE<3:0>
J 0
(-2700 1885);
DISPLAY 0.617021 (-2700 1885);
PAINT ORANGE (-2700 1885);
WIRE 17 -1 (-2800 1750)(-2800 1800);
WIRE 17 -1 (-2800 1700)(-2800 1750);
WIRE 17 -1 (-2800 1350)(-2800 1375);
WIRE 17 -1 (-2800 1300)(-2800 1350);
WIRE 17 -1 (-2050 1375)(-2800 1375);
FORCEPROP 2 LAST SIG_NAME M_G_CS_N<7:0>
J 0
(-2700 1385);
DISPLAY 0.617021 (-2700 1385);
PAINT ORANGE (-2700 1385);
WIRE 17 -1 (-2800 1250)(-2800 1300);
WIRE 17 -1 (-2800 1200)(-2800 1250);
WIRE 17 -1 (-2800 1150)(-2800 1200);
WIRE 17 -1 (-2800 1100)(-2800 1150);
WIRE 17 -1 (-2800 1050)(-2800 1100);
WIRE 17 -1 (-2800 1000)(-2800 1050);
WIRE 17 -1 (-2800 1600)(-2800 1625);
WIRE 17 -1 (-2800 1550)(-2800 1600);
WIRE 17 -1 (-2050 1625)(-2800 1625);
FORCEPROP 2 LAST SIG_NAME M_G_ODT<3:0>
J 0
(-2700 1635);
DISPLAY 0.617021 (-2700 1635);
PAINT ORANGE (-2700 1635);
WIRE 17 -1 (-2800 1500)(-2800 1550);
WIRE 17 -1 (-2800 1450)(-2800 1500);
WIRE 17 -1 (-5625 4700)(-5625 4800);
WIRE 17 -1 (-5625 4650)(-5625 4700);
WIRE 17 -1 (-5625 4800)(-6375 4800);
FORCEPROP 2 LAST SIG_NAME M_G_DQ<63:0>
J 0
(-6325 4810);
DISPLAY 0.617021 (-6325 4810);
PAINT ORANGE (-6325 4810);
WIRE 17 -1 (-5625 4600)(-5625 4650);
WIRE 17 -1 (-5625 4550)(-5625 4600);
WIRE 17 -1 (-5625 4500)(-5625 4550);
WIRE 17 -1 (-5625 4450)(-5625 4500);
WIRE 17 -1 (-5625 4400)(-5625 4450);
WIRE 17 -1 (-5625 4350)(-5625 4400);
WIRE 17 -1 (-5625 4300)(-5625 4350);
WIRE 17 -1 (-5625 4250)(-5625 4300);
WIRE 17 -1 (-5625 4200)(-5625 4250);
WIRE 17 -1 (-5625 4150)(-5625 4200);
WIRE 17 -1 (-5625 4100)(-5625 4150);
WIRE 17 -1 (-5625 4050)(-5625 4100);
WIRE 17 -1 (-5625 4000)(-5625 4050);
WIRE 17 -1 (-5625 3950)(-5625 4000);
WIRE 17 -1 (-5625 3900)(-5625 3950);
WIRE 17 -1 (-5625 3850)(-5625 3900);
WIRE 17 -1 (-5625 3800)(-5625 3850);
WIRE 17 -1 (-5625 3750)(-5625 3800);
WIRE 17 -1 (-5625 3700)(-5625 3750);
WIRE 17 -1 (-5625 3650)(-5625 3700);
WIRE 17 -1 (-5625 3600)(-5625 3650);
WIRE 17 -1 (-5625 3550)(-5625 3600);
WIRE 17 -1 (-5625 3500)(-5625 3550);
WIRE 17 -1 (-5625 3450)(-5625 3500);
WIRE 17 -1 (-5625 3400)(-5625 3450);
WIRE 17 -1 (-5625 3350)(-5625 3400);
WIRE 17 -1 (-5625 3300)(-5625 3350);
WIRE 17 -1 (-5625 3250)(-5625 3300);
WIRE 17 -1 (-5625 3200)(-5625 3250);
WIRE 17 -1 (-5625 3150)(-5625 3200);
WIRE 17 -1 (-5625 3100)(-5625 3150);
WIRE 17 -1 (-5625 3050)(-5625 3100);
WIRE 17 -1 (-5625 3000)(-5625 3050);
WIRE 17 -1 (-5625 2950)(-5625 3000);
WIRE 17 -1 (-5625 2900)(-5625 2950);
WIRE 17 -1 (-5625 2850)(-5625 2900);
WIRE 17 -1 (-5625 2800)(-5625 2850);
WIRE 17 -1 (-5625 2750)(-5625 2800);
WIRE 17 -1 (-5625 2700)(-5625 2750);
WIRE 17 -1 (-5625 2650)(-5625 2700);
WIRE 17 -1 (-5625 2600)(-5625 2650);
WIRE 17 -1 (-5625 2550)(-5625 2600);
WIRE 17 -1 (-5625 2500)(-5625 2550);
WIRE 17 -1 (-5625 2450)(-5625 2500);
WIRE 17 -1 (-5625 2400)(-5625 2450);
WIRE 17 -1 (-5625 2350)(-5625 2400);
WIRE 17 -1 (-5625 2300)(-5625 2350);
WIRE 17 -1 (-5625 2250)(-5625 2300);
WIRE 17 -1 (-5625 2200)(-5625 2250);
WIRE 17 -1 (-5625 2150)(-5625 2200);
WIRE 17 -1 (-5625 2100)(-5625 2150);
WIRE 17 -1 (-5625 2050)(-5625 2100);
WIRE 17 -1 (-5625 2000)(-5625 2050);
WIRE 17 -1 (-5625 1950)(-5625 2000);
WIRE 17 -1 (-5625 1900)(-5625 1950);
WIRE 17 -1 (-5625 1850)(-5625 1900);
WIRE 17 -1 (-5625 1800)(-5625 1850);
WIRE 17 -1 (-5625 1750)(-5625 1800);
WIRE 17 -1 (-5625 1700)(-5625 1750);
WIRE 17 -1 (-5625 1650)(-5625 1700);
WIRE 17 -1 (-5625 1600)(-5625 1650);
WIRE 17 -1 (-5625 1550)(-5625 1600);
WIRE 17 -1 (-5625 800)(-5625 825);
WIRE 17 -1 (-5625 750)(-5625 800);
WIRE 17 -1 (-5625 825)(-6375 825);
FORCEPROP 2 LAST SIG_NAME M_G_CLK_DN<3:0>
J 0
(-6325 835);
DISPLAY 0.617021 (-6325 835);
PAINT ORANGE (-6325 835);
WIRE 17 -1 (-5625 700)(-5625 750);
WIRE 17 -1 (-5625 650)(-5625 700);
WIRE 17 -1 (-5625 1000)(-5625 1025);
WIRE 17 -1 (-5625 950)(-5625 1000);
WIRE 17 -1 (-5625 1025)(-6375 1025);
FORCEPROP 2 LAST SIG_NAME M_G_CLK_DP<3:0>
J 0
(-6325 1035);
DISPLAY 0.617021 (-6325 1035);
PAINT ORANGE (-6325 1035);
WIRE 17 -1 (-5625 900)(-5625 950);
WIRE 17 -1 (-5625 850)(-5625 900);
WIRE 17 -1 (-5625 1450)(-5625 1475);
WIRE 17 -1 (-5625 1400)(-5625 1450);
WIRE 17 -1 (-5625 1475)(-6375 1475);
FORCEPROP 2 LAST SIG_NAME M_G_ECC<7:0>
J 0
(-6325 1485);
DISPLAY 0.617021 (-6325 1485);
PAINT ORANGE (-6325 1485);
WIRE 17 -1 (-5625 1350)(-5625 1400);
WIRE 17 -1 (-5625 1300)(-5625 1350);
WIRE 17 -1 (-5625 1250)(-5625 1300);
WIRE 17 -1 (-5625 1200)(-5625 1250);
WIRE 17 -1 (-5625 1150)(-5625 1200);
WIRE 17 -1 (-5625 1100)(-5625 1150);
WIRE 16 -1 (-5025 525)(-6375 525);
FORCEPROP 2 LAST SIG_NAME M_G_C<2>
J 0
(-6325 535);
DISPLAY 0.617021 (-6325 535);
PAINT ORANGE (-6325 535);
WIRE 16 -1 (-5025 1075)(-5525 1075);
WIRE 16 -1 (-5025 1125)(-5525 1125);
WIRE 16 -1 (-5025 1175)(-5525 1175);
WIRE 16 -1 (-5025 1225)(-5525 1225);
WIRE 16 -1 (-5025 1275)(-5525 1275);
WIRE 16 -1 (-5025 1325)(-5525 1325);
WIRE 16 -1 (-5025 1375)(-5525 1375);
WIRE 16 -1 (-5025 1425)(-5525 1425);
WIRE 16 -1 (-5525 1525)(-5025 1525);
WIRE 16 -1 (-5525 1575)(-5025 1575);
WIRE 16 -1 (-5525 1625)(-5025 1625);
WIRE 16 -1 (-5025 1675)(-5525 1675);
WIRE 16 -1 (-5525 1725)(-5025 1725);
WIRE 16 -1 (-5525 1775)(-5025 1775);
WIRE 16 -1 (-5025 1825)(-5525 1825);
WIRE 16 -1 (-5525 1875)(-5025 1875);
WIRE 16 -1 (-5525 1925)(-5025 1925);
WIRE 16 -1 (-5525 1975)(-5025 1975);
WIRE 16 -1 (-5525 2025)(-5025 2025);
WIRE 16 -1 (-5025 825)(-5525 825);
WIRE 16 -1 (-5025 875)(-5525 875);
WIRE 16 -1 (-5025 925)(-5525 925);
WIRE 16 -1 (-5025 975)(-5525 975);
WIRE 16 -1 (-5025 625)(-5525 625);
WIRE 16 -1 (-5025 675)(-5525 675);
WIRE 16 -1 (-5025 725)(-5525 725);
WIRE 16 -1 (-5025 775)(-5525 775);
WIRE 16 -1 (-5525 2075)(-5025 2075);
WIRE 16 -1 (-5525 2125)(-5025 2125);
WIRE 16 -1 (-5525 2175)(-5025 2175);
WIRE 16 -1 (-5525 2225)(-5025 2225);
WIRE 16 -1 (-5025 2275)(-5525 2275);
WIRE 16 -1 (-5525 2325)(-5025 2325);
WIRE 16 -1 (-5525 2375)(-5025 2375);
WIRE 16 -1 (-5025 2425)(-5525 2425);
WIRE 16 -1 (-5525 2475)(-5025 2475);
WIRE 16 -1 (-5525 2525)(-5025 2525);
WIRE 16 -1 (-5525 2575)(-5025 2575);
WIRE 16 -1 (-5525 2625)(-5025 2625);
WIRE 16 -1 (-5025 2675)(-5525 2675);
WIRE 16 -1 (-5525 2725)(-5025 2725);
WIRE 16 -1 (-5525 2775)(-5025 2775);
WIRE 16 -1 (-5525 2825)(-5025 2825);
WIRE 16 -1 (-5525 2875)(-5025 2875);
WIRE 16 -1 (-5525 2925)(-5025 2925);
WIRE 16 -1 (-5525 2975)(-5025 2975);
WIRE 16 -1 (-5025 3025)(-5525 3025);
WIRE 16 -1 (-5525 3075)(-5025 3075);
WIRE 16 -1 (-5525 3125)(-5025 3125);
WIRE 16 -1 (-5525 3175)(-5025 3175);
WIRE 16 -1 (-5525 3225)(-5025 3225);
WIRE 16 -1 (-5525 3275)(-5025 3275);
WIRE 16 -1 (-5525 3325)(-5025 3325);
WIRE 16 -1 (-5025 3375)(-5525 3375);
WIRE 16 -1 (-5525 3425)(-5025 3425);
WIRE 16 -1 (-5525 3475)(-5025 3475);
WIRE 16 -1 (-5025 3525)(-5525 3525);
WIRE 16 -1 (-5525 3575)(-5025 3575);
WIRE 16 -1 (-5525 3625)(-5025 3625);
WIRE 16 -1 (-5025 3675)(-5525 3675);
WIRE 16 -1 (-5025 3725)(-5525 3725);
WIRE 16 -1 (-5025 3775)(-5525 3775);
WIRE 16 -1 (-5025 3825)(-5525 3825);
WIRE 16 -1 (-5025 3875)(-5525 3875);
WIRE 16 -1 (-5025 3925)(-5525 3925);
WIRE 16 -1 (-5025 3975)(-5525 3975);
WIRE 16 -1 (-5025 4025)(-5525 4025);
WIRE 16 -1 (-5025 4075)(-5525 4075);
WIRE 16 -1 (-5025 4125)(-5525 4125);
WIRE 16 -1 (-5025 4175)(-5525 4175);
WIRE 16 -1 (-5025 4225)(-5525 4225);
WIRE 16 -1 (-5025 4275)(-5525 4275);
WIRE 16 -1 (-5025 4325)(-5525 4325);
WIRE 16 -1 (-5025 4375)(-5525 4375);
WIRE 16 -1 (-5025 4425)(-5525 4425);
WIRE 16 -1 (-5025 4475)(-5525 4475);
WIRE 16 -1 (-5025 4525)(-5525 4525);
WIRE 16 -1 (-5025 4575)(-5525 4575);
WIRE 16 -1 (-5025 4625)(-5525 4625);
WIRE 16 -1 (-5025 4675)(-5525 4675);
WIRE 16 -1 (-3325 1425)(-2900 1425);
WIRE 16 -1 (-3325 1475)(-2900 1475);
WIRE 16 -1 (-3325 1525)(-2900 1525);
WIRE 16 -1 (-3325 1575)(-2900 1575);
WIRE 16 -1 (-3325 1925)(-2900 1925);
WIRE 16 -1 (-3325 1975)(-2900 1975);
WIRE 16 -1 (-3325 2025)(-2900 2025);
WIRE 16 -1 (-3325 975)(-2900 975);
WIRE 16 -1 (-3325 1025)(-2900 1025);
WIRE 16 -1 (-3325 1075)(-2900 1075);
WIRE 16 -1 (-3325 1125)(-2900 1125);
WIRE 16 -1 (-3325 1175)(-2900 1175);
WIRE 16 -1 (-3325 1225)(-2900 1225);
WIRE 16 -1 (-3325 1275)(-2900 1275);
WIRE 16 -1 (-3325 1325)(-2900 1325);
WIRE 16 -1 (-3325 1675)(-2900 1675);
WIRE 16 -1 (-3325 1725)(-2900 1725);
WIRE 16 -1 (-3325 1775)(-2900 1775);
WIRE 16 -1 (-3325 1825)(-2900 1825);
WIRE 16 -1 (-3325 825)(-2900 825);
WIRE 16 -1 (-3325 875)(-2900 875);
WIRE 16 -1 (-3325 725)(-2900 725);
WIRE 16 -1 (-3325 775)(-2900 775);
WIRE 16 -1 (-3325 525)(-2050 525);
FORCEPROP 2 LAST SIG_NAME M_G_PAR
J 0
(-2700 535);
DISPLAY 0.617021 (-2700 535);
PAINT ORANGE (-2700 535);
WIRE 16 -1 (-3325 575)(-2050 575);
FORCEPROP 2 LAST SIG_NAME M_G_ALERT_N
J 0
(-2700 585);
DISPLAY 0.617021 (-2700 585);
PAINT ORANGE (-2700 585);
WIRE 16 -1 (-3325 625)(-2050 625);
FORCEPROP 2 LAST SIG_NAME M_G_ACT_N
J 0
(-2700 635);
DISPLAY 0.617021 (-2700 635);
PAINT ORANGE (-2700 635);
WIRE 16 -1 (-3325 2075)(-2900 2075);
WIRE 16 -1 (-3325 2125)(-2900 2125);
WIRE 16 -1 (-3325 2175)(-2900 2175);
WIRE 16 -1 (-3325 2225)(-2900 2225);
WIRE 16 -1 (-3325 2275)(-2900 2275);
WIRE 16 -1 (-3325 2325)(-2900 2325);
WIRE 16 -1 (-3325 2375)(-2900 2375);
WIRE 16 -1 (-3325 2425)(-2900 2425);
WIRE 16 -1 (-3325 2475)(-2900 2475);
WIRE 16 -1 (-3325 2525)(-2900 2525);
WIRE 16 -1 (-3325 2575)(-2900 2575);
WIRE 16 -1 (-3325 2625)(-2900 2625);
WIRE 16 -1 (-3325 2675)(-2900 2675);
WIRE 16 -1 (-3325 2725)(-2900 2725);
WIRE 16 -1 (-3325 2775)(-2900 2775);
WIRE 16 -1 (-3325 3825)(-2900 3825);
WIRE 16 -1 (-3325 3875)(-2900 3875);
WIRE 16 -1 (-3325 3925)(-2900 3925);
WIRE 16 -1 (-3325 3975)(-2900 3975);
WIRE 16 -1 (-3325 4025)(-2900 4025);
WIRE 16 -1 (-3325 4075)(-2900 4075);
WIRE 16 -1 (-3325 2875)(-2900 2875);
WIRE 16 -1 (-3325 2925)(-2900 2925);
WIRE 16 -1 (-3325 2975)(-2900 2975);
WIRE 16 -1 (-3325 3025)(-2900 3025);
WIRE 16 -1 (-3325 3075)(-2900 3075);
WIRE 16 -1 (-3325 3125)(-2900 3125);
WIRE 16 -1 (-3325 3175)(-2900 3175);
WIRE 16 -1 (-3325 3225)(-2900 3225);
WIRE 16 -1 (-3325 3275)(-2900 3275);
WIRE 16 -1 (-3325 3325)(-2900 3325);
WIRE 16 -1 (-3325 3375)(-2900 3375);
WIRE 16 -1 (-3325 3425)(-2900 3425);
WIRE 16 -1 (-3325 3475)(-2900 3475);
WIRE 16 -1 (-3325 3525)(-2900 3525);
WIRE 16 -1 (-3325 3575)(-2900 3575);
WIRE 16 -1 (-3325 3625)(-2900 3625);
WIRE 16 -1 (-3325 3675)(-2900 3675);
WIRE 16 -1 (-3325 3725)(-2900 3725);
WIRE 16 -1 (-3325 4125)(-2900 4125);
WIRE 16 -1 (-3325 4175)(-2900 4175);
WIRE 16 -1 (-3325 4225)(-2900 4225);
WIRE 16 -1 (-3325 4275)(-2900 4275);
WIRE 16 -1 (-3325 4325)(-2900 4325);
WIRE 16 -1 (-3325 4375)(-2900 4375);
WIRE 16 -1 (-3325 4425)(-2900 4425);
WIRE 16 -1 (-3325 4475)(-2900 4475);
WIRE 16 -1 (-3325 4525)(-2900 4525);
WIRE 16 -1 (-3325 4575)(-2900 4575);
WIRE 16 -1 (-3325 4625)(-2900 4625);
WIRE 16 -1 (-3325 4675)(-2900 4675);
FORCENOTE
BOM_COST=PROC_SOCKET
(-7925 275) 0;
DISPLAY LEFT (-7925 275);
DISPLAY 1.723404 (-7925 275);
PAINT PURPLE (-7925 275);
FORCENOTE
ROOM=CPU1
(-7925 400) 0;
DISPLAY LEFT (-7925 400);
DISPLAY 1.723404 (-7925 400);
PAINT PURPLE (-7925 400);
QUIT
